(kicad_sch
	(version 20250114)
	(generator "eeschema")
	(generator_version "9.0")
	(paper "A3")
	(title_block
		(title "PolarFire SoM")
		(date "2025-07-22")
		(rev "1.1.4")
		(company "Antmicro Ltd")
		(comment 1 "www.antmicro.com")
	)
	(bus_alias "CSI"
		(members "D0_P" "D0_N" "D1_P" "D1_N" "C_P" "C_N" "D2_P" "D2_N" "D3_P" "D3_N")
	)
	(bus_alias "DSI"
		(members "D0_P" "D0_N" "D1_P" "D1_N" "C_P" "C_N" "D2_P" "D2_N" "D3_P" "D3_N")
	)
	(bus_alias "PCIe_x4"
		(members "RXD0_P" "RXD0_N" "RXD1_P" "RXD1_N" "RXD2_P" "RXD2_N" "RXD3_P"
			"RXD3_N" "TXD0_P" "TXD0_N" "TXD1_P" "TXD1_N" "TXD2_P" "TXD2_N" "TXD3_P"
			"TXD3_N" "CLK_P" "CLK_N"
		)
	)
	(text "PCIE_TX_P"
		(exclude_from_sim no)
		(at 276.86 98.425 0)
		(effects
			(font
				(size 1.27 1.27)
			)
			(justify left bottom)
		)
	)
	(text "CAM1_D1_P"
		(exclude_from_sim no)
		(at 180.34 105.41 0)
		(effects
			(font
				(size 1.27 1.27)
			)
			(justify right bottom)
		)
	)
	(text "DSI1_D3_P"
		(exclude_from_sim no)
		(at 276.86 195.58 0)
		(effects
			(font
				(size 1.27 1.27)
			)
			(justify left bottom)
		)
	)
	(text "DSI1_D1_P"
		(exclude_from_sim no)
		(at 182.88 181.61 0)
		(effects
			(font
				(size 1.27 1.27)
			)
			(justify right bottom)
		)
	)
	(text "DSI0_C_P"
		(exclude_from_sim no)
		(at 193.04 166.37 0)
		(effects
			(font
				(size 1.27 1.27)
			)
			(justify right bottom)
		)
	)
	(text "DSI1_D1_N"
		(exclude_from_sim no)
		(at 172.72 179.07 0)
		(effects
			(font
				(size 1.27 1.27)
			)
			(justify left bottom)
		)
	)
	(text "DSI0_D0_N"
		(exclude_from_sim no)
		(at 181.61 148.59 0)
		(effects
			(font
				(size 1.27 1.27)
			)
			(justify right bottom)
		)
	)
	(text "HDMI1_SDA"
		(exclude_from_sim no)
		(at 207.01 134.62 0)
		(effects
			(font
				(size 1.27 1.27)
			)
			(justify right bottom)
		)
	)
	(text "CAM1_D1_N"
		(exclude_from_sim no)
		(at 180.34 102.87 0)
		(effects
			(font
				(size 1.27 1.27)
			)
			(justify right bottom)
		)
	)
	(text "DSI0_D1_P"
		(exclude_from_sim no)
		(at 181.61 158.75 0)
		(effects
			(font
				(size 1.27 1.27)
			)
			(justify right bottom)
		)
	)
	(text "HDMI1_CLK_N"
		(exclude_from_sim no)
		(at 276.86 154.94 0)
		(effects
			(font
				(size 1.27 1.27)
			)
			(justify left bottom)
		)
	)
	(text "CAM1_C_N"
		(exclude_from_sim no)
		(at 180.34 110.49 0)
		(effects
			(font
				(size 1.27 1.27)
			)
			(justify right bottom)
		)
	)
	(text "DSI0_D1_N"
		(exclude_from_sim no)
		(at 181.61 156.21 0)
		(effects
			(font
				(size 1.27 1.27)
			)
			(justify right bottom)
		)
	)
	(text "CAM1_C_P"
		(exclude_from_sim no)
		(at 180.34 113.03 0)
		(effects
			(font
				(size 1.27 1.27)
			)
			(justify right bottom)
		)
	)
	(text "HDMI0_TX1_N"
		(exclude_from_sim no)
		(at 276.86 172.72 0)
		(effects
			(font
				(size 1.27 1.27)
			)
			(justify left bottom)
		)
	)
	(text "HDMI0_CLK_P"
		(exclude_from_sim no)
		(at 276.86 182.88 0)
		(effects
			(font
				(size 1.27 1.27)
			)
			(justify left bottom)
		)
	)
	(text "reserved\n"
		(exclude_from_sim no)
		(at 263.525 81.915 0)
		(effects
			(font
				(size 1.27 1.27)
			)
			(justify left bottom)
		)
	)
	(text "HDMI1_TX1_N"
		(exclude_from_sim no)
		(at 276.86 142.24 0)
		(effects
			(font
				(size 1.27 1.27)
			)
			(justify left bottom)
		)
	)
	(text "HDMI1_TX2_P"
		(exclude_from_sim no)
		(at 276.86 133.35 0)
		(effects
			(font
				(size 1.27 1.27)
			)
			(justify left bottom)
		)
	)
	(text "DSI1_D2_P"
		(exclude_from_sim no)
		(at 182.88 195.58 0)
		(effects
			(font
				(size 1.27 1.27)
			)
			(justify right bottom)
		)
	)
	(text "HDMI1_TX1_P"
		(exclude_from_sim no)
		(at 276.86 139.7 0)
		(effects
			(font
				(size 1.27 1.27)
			)
			(justify left bottom)
		)
	)
	(text "HDMI0_TX2_N"
		(exclude_from_sim no)
		(at 276.86 166.37 0)
		(effects
			(font
				(size 1.27 1.27)
			)
			(justify left bottom)
		)
	)
	(text "CAM0_D1_P"
		(exclude_from_sim no)
		(at 276.86 119.38 0)
		(effects
			(font
				(size 1.27 1.27)
			)
			(justify left bottom)
		)
	)
	(text "DSI1_D2_N"
		(exclude_from_sim no)
		(at 182.88 193.04 0)
		(effects
			(font
				(size 1.27 1.27)
			)
			(justify right bottom)
		)
	)
	(text "DSI1_C_P"
		(exclude_from_sim no)
		(at 182.88 189.23 0)
		(effects
			(font
				(size 1.27 1.27)
			)
			(justify right bottom)
		)
	)
	(text "CAM1_D2_P"
		(exclude_from_sim no)
		(at 180.34 120.65 0)
		(effects
			(font
				(size 1.27 1.27)
			)
			(justify right bottom)
		)
	)
	(text "HDMI1_SCL"
		(exclude_from_sim no)
		(at 207.01 137.16 0)
		(effects
			(font
				(size 1.27 1.27)
			)
			(justify right bottom)
		)
	)
	(text "CAM1_D3_N"
		(exclude_from_sim no)
		(at 180.34 125.73 0)
		(effects
			(font
				(size 1.27 1.27)
			)
			(justify right bottom)
		)
	)
	(text "CAM0_D0_P"
		(exclude_from_sim no)
		(at 276.86 113.03 0)
		(effects
			(font
				(size 1.27 1.27)
			)
			(justify left bottom)
		)
	)
	(text "reserved"
		(exclude_from_sim no)
		(at 263.525 84.455 0)
		(effects
			(font
				(size 1.27 1.27)
			)
			(justify left bottom)
		)
	)
	(text "HDMI0_CLK_N"
		(exclude_from_sim no)
		(at 276.86 185.42 0)
		(effects
			(font
				(size 1.27 1.27)
			)
			(justify left bottom)
		)
	)
	(text "PCIe_CLK_nREQ"
		(exclude_from_sim no)
		(at 277.495 78.105 0)
		(effects
			(font
				(size 1.27 1.27)
			)
			(justify left bottom)
		)
	)
	(text "DSI1_D0_N"
		(exclude_from_sim no)
		(at 172.72 171.45 0)
		(effects
			(font
				(size 1.27 1.27)
			)
			(justify left bottom)
		)
	)
	(text "DSI1_D0_P"
		(exclude_from_sim no)
		(at 182.88 173.99 0)
		(effects
			(font
				(size 1.27 1.27)
			)
			(justify right bottom)
		)
	)
	(text "PCIE_CLK_N"
		(exclude_from_sim no)
		(at 276.86 89.535 0)
		(effects
			(font
				(size 1.27 1.27)
			)
			(justify left bottom)
		)
	)
	(text "HDMI0_SDA"
		(exclude_from_sim no)
		(at 182.245 202.565 0)
		(effects
			(font
				(size 1.27 1.27)
			)
			(justify right bottom)
		)
	)
	(text "PCIE_RX_P"
		(exclude_from_sim no)
		(at 276.86 93.345 0)
		(effects
			(font
				(size 1.27 1.27)
			)
			(justify left bottom)
		)
	)
	(text "HDMI0_TX2_P"
		(exclude_from_sim no)
		(at 276.86 163.83 0)
		(effects
			(font
				(size 1.27 1.27)
			)
			(justify left bottom)
		)
	)
	(text "CAM1_D0_P"
		(exclude_from_sim no)
		(at 180.34 97.79 0)
		(effects
			(font
				(size 1.27 1.27)
			)
			(justify right bottom)
		)
	)
	(text "HDMI1_CEC"
		(exclude_from_sim no)
		(at 207.01 139.7 0)
		(effects
			(font
				(size 1.27 1.27)
			)
			(justify right bottom)
		)
	)
	(text "HDMI1_TX0_N"
		(exclude_from_sim no)
		(at 276.86 148.59 0)
		(effects
			(font
				(size 1.27 1.27)
			)
			(justify left bottom)
		)
	)
	(text "PCIE_CLK_P"
		(exclude_from_sim no)
		(at 276.86 87.63 0)
		(effects
			(font
				(size 1.27 1.27)
			)
			(justify left bottom)
		)
	)
	(text "HDMI0_HOTPLUG"
		(exclude_from_sim no)
		(at 194.31 142.24 0)
		(effects
			(font
				(size 1.27 1.27)
			)
			(justify right bottom)
		)
	)
	(text "VDAC_COMP"
		(exclude_from_sim no)
		(at 196.85 91.44 0)
		(effects
			(font
				(size 1.27 1.27)
			)
			(justify right bottom)
		)
	)
	(text "DSI1_D3_N"
		(exclude_from_sim no)
		(at 276.86 193.04 0)
		(effects
			(font
				(size 1.27 1.27)
			)
			(justify left bottom)
		)
	)
	(text "PCIe_nRST"
		(exclude_from_sim no)
		(at 196.85 88.9 0)
		(effects
			(font
				(size 1.27 1.27)
			)
			(justify right bottom)
		)
	)
	(text "CAM1_D3_P"
		(exclude_from_sim no)
		(at 180.34 128.27 0)
		(effects
			(font
				(size 1.27 1.27)
			)
			(justify right bottom)
		)
	)
	(text "DSI0_D0_P"
		(exclude_from_sim no)
		(at 181.61 151.13 0)
		(effects
			(font
				(size 1.27 1.27)
			)
			(justify right bottom)
		)
	)
	(text "HDMI0_CEC"
		(exclude_from_sim no)
		(at 207.01 142.24 0)
		(effects
			(font
				(size 1.27 1.27)
			)
			(justify right bottom)
		)
	)
	(text "PCIE_RX_N"
		(exclude_from_sim no)
		(at 276.86 95.25 0)
		(effects
			(font
				(size 1.27 1.27)
			)
			(justify left bottom)
		)
	)
	(text "DSI1_C_N"
		(exclude_from_sim no)
		(at 182.88 186.69 0)
		(effects
			(font
				(size 1.27 1.27)
			)
			(justify right bottom)
		)
	)
	(text "HDMI0_TX1_P"
		(exclude_from_sim no)
		(at 276.86 170.18 0)
		(effects
			(font
				(size 1.27 1.27)
			)
			(justify left bottom)
		)
	)
	(text "PCIE_TX_N"
		(exclude_from_sim no)
		(at 276.86 100.33 0)
		(effects
			(font
				(size 1.27 1.27)
			)
			(justify left bottom)
		)
	)
	(text "CAM1_D0_N"
		(exclude_from_sim no)
		(at 180.34 95.25 0)
		(effects
			(font
				(size 1.27 1.27)
			)
			(justify right bottom)
		)
	)
	(text "CAM0_D0_N"
		(exclude_from_sim no)
		(at 276.86 110.49 0)
		(effects
			(font
				(size 1.27 1.27)
			)
			(justify left bottom)
		)
	)
	(text "HDMI1_CLK_P"
		(exclude_from_sim no)
		(at 276.86 152.4 0)
		(effects
			(font
				(size 1.27 1.27)
			)
			(justify left bottom)
		)
	)
	(text "HDMI1_HOTPLUG"
		(exclude_from_sim no)
		(at 207.01 132.08 0)
		(effects
			(font
				(size 1.27 1.27)
			)
			(justify right bottom)
		)
	)
	(text "DSI0_C_N"
		(exclude_from_sim no)
		(at 193.04 163.83 0)
		(effects
			(font
				(size 1.27 1.27)
			)
			(justify right bottom)
		)
	)
	(text "HDMI0_TX0_P"
		(exclude_from_sim no)
		(at 276.86 176.53 0)
		(effects
			(font
				(size 1.27 1.27)
			)
			(justify left bottom)
		)
	)
	(text "HDMI1_TX0_P"
		(exclude_from_sim no)
		(at 276.86 146.05 0)
		(effects
			(font
				(size 1.27 1.27)
			)
			(justify left bottom)
		)
	)
	(text "CAM1_D2_N"
		(exclude_from_sim no)
		(at 180.34 118.11 0)
		(effects
			(font
				(size 1.27 1.27)
			)
			(justify right bottom)
		)
	)
	(text "CAM0_C_N"
		(exclude_from_sim no)
		(at 276.86 123.19 0)
		(effects
			(font
				(size 1.27 1.27)
			)
			(justify left bottom)
		)
	)
	(text "HDMI0_SCL"
		(exclude_from_sim no)
		(at 276.86 201.93 0)
		(effects
			(font
				(size 1.27 1.27)
			)
			(justify left bottom)
		)
	)
	(text "HDMI0_TX0_N"
		(exclude_from_sim no)
		(at 276.86 179.07 0)
		(effects
			(font
				(size 1.27 1.27)
			)
			(justify left bottom)
		)
	)
	(text "CAM0_D1_N"
		(exclude_from_sim no)
		(at 276.86 116.84 0)
		(effects
			(font
				(size 1.27 1.27)
			)
			(justify left bottom)
		)
	)
	(text "HDMI1_TX2_N"
		(exclude_from_sim no)
		(at 276.86 135.89 0)
		(effects
			(font
				(size 1.27 1.27)
			)
			(justify left bottom)
		)
	)
	(text "CAM0_C_P"
		(exclude_from_sim no)
		(at 276.86 125.73 0)
		(effects
			(font
				(size 1.27 1.27)
			)
			(justify left bottom)
		)
	)
	(junction
		(at 224.79 176.53)
		(diameter 0)
		(color 0 0 0 0)
	)
	(junction
		(at 224.79 92.71)
		(diameter 0)
		(color 0 0 0 0)
	)
	(junction
		(at 243.84 191.77)
		(diameter 0)
		(color 0 0 0 0)
	)
	(junction
		(at 224.79 153.67)
		(diameter 0)
		(color 0 0 0 0)
	)
	(junction
		(at 222.25 135.89)
		(diameter 0)
		(color 0 0 0 0)
	)
	(junction
		(at 224.79 107.95)
		(diameter 0)
		(color 0 0 0 0)
	)
	(junction
		(at 243.84 153.67)
		(diameter 0)
		(color 0 0 0 0)
	)
	(junction
		(at 243.84 204.47)
		(diameter 0)
		(color 0 0 0 0)
	)
	(junction
		(at 224.79 161.29)
		(diameter 0)
		(color 0 0 0 0)
	)
	(junction
		(at 243.84 176.53)
		(diameter 0)
		(color 0 0 0 0)
	)
	(junction
		(at 222.25 133.35)
		(diameter 0)
		(color 0 0 0 0)
	)
	(junction
		(at 130.81 134.62)
		(diameter 0)
		(color 0 0 0 0)
	)
	(junction
		(at 243.84 107.95)
		(diameter 0)
		(color 0 0 0 0)
	)
	(junction
		(at 224.79 191.77)
		(diameter 0)
		(color 0 0 0 0)
	)
	(junction
		(at 224.79 146.05)
		(diameter 0)
		(color 0 0 0 0)
	)
	(junction
		(at 243.84 138.43)
		(diameter 0)
		(color 0 0 0 0)
	)
	(junction
		(at 101.6 134.62)
		(diameter 0)
		(color 0 0 0 0)
	)
	(junction
		(at 127 134.62)
		(diameter 0)
		(color 0 0 0 0)
	)
	(junction
		(at 125.73 134.62)
		(diameter 0)
		(color 0 0 0 0)
	)
	(junction
		(at 243.84 184.15)
		(diameter 0)
		(color 0 0 0 0)
	)
	(junction
		(at 224.79 123.19)
		(diameter 0)
		(color 0 0 0 0)
	)
	(junction
		(at 224.79 115.57)
		(diameter 0)
		(color 0 0 0 0)
	)
	(junction
		(at 243.84 115.57)
		(diameter 0)
		(color 0 0 0 0)
	)
	(junction
		(at 243.84 146.05)
		(diameter 0)
		(color 0 0 0 0)
	)
	(junction
		(at 243.84 168.91)
		(diameter 0)
		(color 0 0 0 0)
	)
	(junction
		(at 224.79 100.33)
		(diameter 0)
		(color 0 0 0 0)
	)
	(junction
		(at 102.87 134.62)
		(diameter 0)
		(color 0 0 0 0)
	)
	(junction
		(at 224.79 168.91)
		(diameter 0)
		(color 0 0 0 0)
	)
	(junction
		(at 224.79 199.39)
		(diameter 0)
		(color 0 0 0 0)
	)
	(junction
		(at 100.33 151.13)
		(diameter 0)
		(color 0 0 0 0)
	)
	(junction
		(at 224.79 184.15)
		(diameter 0)
		(color 0 0 0 0)
	)
	(junction
		(at 243.84 92.71)
		(diameter 0)
		(color 0 0 0 0)
	)
	(junction
		(at 222.25 134.62)
		(diameter 0)
		(color 0 0 0 0)
	)
	(junction
		(at 243.84 161.29)
		(diameter 0)
		(color 0 0 0 0)
	)
	(junction
		(at 243.84 199.39)
		(diameter 0)
		(color 0 0 0 0)
	)
	(junction
		(at 243.84 100.33)
		(diameter 0)
		(color 0 0 0 0)
	)
	(junction
		(at 243.84 123.19)
		(diameter 0)
		(color 0 0 0 0)
	)
	(junction
		(at 243.84 130.81)
		(diameter 0)
		(color 0 0 0 0)
	)
	(no_connect
		(at 222.25 140.97)
	)
	(no_connect
		(at 227.33 163.83)
	)
	(no_connect
		(at 227.33 90.17)
	)
	(no_connect
		(at 241.3 80.01)
	)
	(no_connect
		(at 241.3 82.55)
	)
	(no_connect
		(at 227.33 166.37)
	)
	(bus_entry
		(at 273.05 166.37)
		(size 2.54 -2.54)
		(stroke
			(width 0)
			(type default)
		)
	)
	(bus_entry
		(at 273.05 102.87)
		(size 2.54 -2.54)
		(stroke
			(width 0)
			(type default)
		)
	)
	(bus_entry
		(at 273.05 148.59)
		(size 2.54 -2.54)
		(stroke
			(width 0)
			(type default)
		)
	)
	(bus_entry
		(at 181.61 115.57)
		(size 2.54 2.54)
		(stroke
			(width 0)
			(type default)
		)
	)
	(bus_entry
		(at 273.05 90.17)
		(size 2.54 -2.54)
		(stroke
			(width 0)
			(type default)
		)
	)
	(bus_entry
		(at 273.05 173.99)
		(size 2.54 -2.54)
		(stroke
			(width 0)
			(type default)
		)
	)
	(bus_entry
		(at 273.05 179.07)
		(size 2.54 -2.54)
		(stroke
			(width 0)
			(type default)
		)
	)
	(bus_entry
		(at 181.61 80.01)
		(size 2.54 2.54)
		(stroke
			(width 0)
			(type default)
		)
	)
	(bus_entry
		(at 184.15 194.31)
		(size 2.54 2.54)
		(stroke
			(width 0)
			(type default)
		)
	)
	(bus_entry
		(at 273.05 143.51)
		(size 2.54 -2.54)
		(stroke
			(width 0)
			(type default)
		)
	)
	(bus_entry
		(at 181.61 123.19)
		(size 2.54 2.54)
		(stroke
			(width 0)
			(type default)
		)
	)
	(bus_entry
		(at 181.61 118.11)
		(size 2.54 2.54)
		(stroke
			(width 0)
			(type default)
		)
	)
	(bus_entry
		(at 273.05 135.89)
		(size 2.54 -2.54)
		(stroke
			(width 0)
			(type default)
		)
	)
	(bus_entry
		(at 273.05 186.69)
		(size 2.54 -2.54)
		(stroke
			(width 0)
			(type default)
		)
	)
	(bus_entry
		(at 273.05 158.75)
		(size 2.54 -2.54)
		(stroke
			(width 0)
			(type default)
		)
	)
	(bus_entry
		(at 181.61 77.47)
		(size 2.54 2.54)
		(stroke
			(width 0)
			(type default)
		)
	)
	(bus_entry
		(at 184.15 168.91)
		(size 2.54 2.54)
		(stroke
			(width 0)
			(type default)
		)
	)
	(bus_entry
		(at 273.05 105.41)
		(size 2.54 -2.54)
		(stroke
			(width 0)
			(type default)
		)
	)
	(bus_entry
		(at 181.61 95.25)
		(size 2.54 2.54)
		(stroke
			(width 0)
			(type default)
		)
	)
	(bus_entry
		(at 273.05 97.79)
		(size 2.54 -2.54)
		(stroke
			(width 0)
			(type default)
		)
	)
	(bus_entry
		(at 273.05 133.35)
		(size 2.54 -2.54)
		(stroke
			(width 0)
			(type default)
		)
	)
	(bus_entry
		(at 186.69 151.13)
		(size -2.54 -2.54)
		(stroke
			(width 0)
			(type default)
		)
	)
	(bus_entry
		(at 186.69 158.75)
		(size -2.54 -2.54)
		(stroke
			(width 0)
			(type default)
		)
	)
	(bus_entry
		(at 186.69 148.59)
		(size -2.54 -2.54)
		(stroke
			(width 0)
			(type default)
		)
	)
	(bus_entry
		(at 273.05 189.23)
		(size 2.54 -2.54)
		(stroke
			(width 0)
			(type default)
		)
	)
	(bus_entry
		(at 275.59 110.49)
		(size -2.54 2.54)
		(stroke
			(width 0)
			(type default)
		)
	)
	(bus_entry
		(at 275.59 191.77)
		(size -2.54 2.54)
		(stroke
			(width 0)
			(type default)
		)
	)
	(bus_entry
		(at 275.59 194.31)
		(size -2.54 2.54)
		(stroke
			(width 0)
			(type default)
		)
	)
	(bus_entry
		(at 275.59 115.57)
		(size -2.54 2.54)
		(stroke
			(width 0)
			(type default)
		)
	)
	(bus_entry
		(at 273.05 156.21)
		(size 2.54 -2.54)
		(stroke
			(width 0)
			(type default)
		)
	)
	(bus_entry
		(at 273.05 95.25)
		(size 2.54 -2.54)
		(stroke
			(width 0)
			(type default)
		)
	)
	(bus_entry
		(at 275.59 123.19)
		(size -2.54 2.54)
		(stroke
			(width 0)
			(type default)
		)
	)
	(bus_entry
		(at 184.15 186.69)
		(size 2.54 2.54)
		(stroke
			(width 0)
			(type default)
		)
	)
	(bus_entry
		(at 186.69 201.93)
		(size -2.54 -2.54)
		(stroke
			(width 0)
			(type default)
		)
	)
	(bus_entry
		(at 184.15 171.45)
		(size 2.54 2.54)
		(stroke
			(width 0)
			(type default)
		)
	)
	(bus_entry
		(at 184.15 176.53)
		(size 2.54 2.54)
		(stroke
			(width 0)
			(type default)
		)
	)
	(bus_entry
		(at 184.15 184.15)
		(size 2.54 2.54)
		(stroke
			(width 0)
			(type default)
		)
	)
	(bus_entry
		(at 273.05 151.13)
		(size 2.54 -2.54)
		(stroke
			(width 0)
			(type default)
		)
	)
	(bus_entry
		(at 273.05 181.61)
		(size 2.54 -2.54)
		(stroke
			(width 0)
			(type default)
		)
	)
	(bus_entry
		(at 181.61 92.71)
		(size 2.54 2.54)
		(stroke
			(width 0)
			(type default)
		)
	)
	(bus_entry
		(at 181.61 102.87)
		(size 2.54 2.54)
		(stroke
			(width 0)
			(type default)
		)
	)
	(bus_entry
		(at 273.05 140.97)
		(size 2.54 -2.54)
		(stroke
			(width 0)
			(type default)
		)
	)
	(bus_entry
		(at 275.59 125.73)
		(size -2.54 2.54)
		(stroke
			(width 0)
			(type default)
		)
	)
	(bus_entry
		(at 181.61 107.95)
		(size 2.54 2.54)
		(stroke
			(width 0)
			(type default)
		)
	)
	(bus_entry
		(at 275.59 107.95)
		(size -2.54 2.54)
		(stroke
			(width 0)
			(type default)
		)
	)
	(bus_entry
		(at 181.61 110.49)
		(size 2.54 2.54)
		(stroke
			(width 0)
			(type default)
		)
	)
	(bus_entry
		(at 273.05 163.83)
		(size 2.54 -2.54)
		(stroke
			(width 0)
			(type default)
		)
	)
	(bus_entry
		(at 275.59 118.11)
		(size -2.54 2.54)
		(stroke
			(width 0)
			(type default)
		)
	)
	(bus_entry
		(at 273.05 171.45)
		(size 2.54 -2.54)
		(stroke
			(width 0)
			(type default)
		)
	)
	(bus_entry
		(at 186.69 156.21)
		(size -2.54 -2.54)
		(stroke
			(width 0)
			(type default)
		)
	)
	(bus_entry
		(at 184.15 179.07)
		(size 2.54 2.54)
		(stroke
			(width 0)
			(type default)
		)
	)
	(bus_entry
		(at 273.05 87.63)
		(size 2.54 -2.54)
		(stroke
			(width 0)
			(type default)
		)
	)
	(bus_entry
		(at 184.15 191.77)
		(size 2.54 2.54)
		(stroke
			(width 0)
			(type default)
		)
	)
	(bus_entry
		(at 181.61 100.33)
		(size 2.54 2.54)
		(stroke
			(width 0)
			(type default)
		)
	)
	(bus_entry
		(at 181.61 125.73)
		(size 2.54 2.54)
		(stroke
			(width 0)
			(type default)
		)
	)
	(bus_entry
		(at 273.05 201.93)
		(size 2.54 -2.54)
		(stroke
			(width 0)
			(type default)
		)
	)
	(bus
		(pts
			(xy 181.61 143.51) (xy 182.88 143.51)
		)
		(stroke
			(width 0)
			(type default)
		)
	)
	(wire
		(pts
			(xy 222.25 133.35) (xy 227.33 133.35)
		)
		(stroke
			(width 0)
			(type default)
		)
	)
	(wire
		(pts
			(xy 243.84 123.19) (xy 243.84 130.81)
		)
		(stroke
			(width 0)
			(type default)
		)
	)
	(wire
		(pts
			(xy 184.15 110.49) (xy 227.33 110.49)
		)
		(stroke
			(width 0)
			(type default)
		)
	)
	(bus
		(pts
			(xy 275.59 85.09) (xy 275.59 87.63)
		)
		(stroke
			(width 0)
			(type default)
		)
	)
	(bus
		(pts
			(xy 276.86 158.75) (xy 278.13 158.75)
		)
		(stroke
			(width 0)
			(type default)
		)
	)
	(wire
		(pts
			(xy 241.3 85.09) (xy 243.84 85.09)
		)
		(stroke
			(width 0)
			(type default)
		)
	)
	(bus
		(pts
			(xy 181.61 107.95) (xy 181.61 110.49)
		)
		(stroke
			(width 0)
			(type default)
		)
	)
	(wire
		(pts
			(xy 224.79 146.05) (xy 224.79 153.67)
		)
		(stroke
			(width 0)
			(type default)
		)
	)
	(wire
		(pts
			(xy 241.3 146.05) (xy 243.84 146.05)
		)
		(stroke
			(width 0)
			(type default)
		)
	)
	(bus
		(pts
			(xy 184.15 168.91) (xy 184.15 171.45)
		)
		(stroke
			(width 0)
			(type default)
		)
	)
	(bus
		(pts
			(xy 275.59 87.63) (xy 275.59 92.71)
		)
		(stroke
			(width 0)
			(type default)
		)
	)
	(wire
		(pts
			(xy 222.25 130.81) (xy 227.33 130.81)
		)
		(stroke
			(width 0)
			(type default)
		)
	)
	(wire
		(pts
			(xy 127 134.62) (xy 130.81 134.62)
		)
		(stroke
			(width 0)
			(type default)
		)
	)
	(bus
		(pts
			(xy 181.61 102.87) (xy 181.61 107.95)
		)
		(stroke
			(width 0)
			(type default)
		)
	)
	(wire
		(pts
			(xy 241.3 173.99) (xy 273.05 173.99)
		)
		(stroke
			(width 0)
			(type default)
		)
	)
	(wire
		(pts
			(xy 224.79 100.33) (xy 224.79 107.95)
		)
		(stroke
			(width 0)
			(type default)
		)
	)
	(wire
		(pts
			(xy 241.3 128.27) (xy 273.05 128.27)
		)
		(stroke
			(width 0)
			(type default)
		)
	)
	(wire
		(pts
			(xy 186.69 201.93) (xy 227.33 201.93)
		)
		(stroke
			(width 0)
			(type default)
		)
	)
	(wire
		(pts
			(xy 243.84 92.71) (xy 243.84 100.33)
		)
		(stroke
			(width 0)
			(type default)
		)
	)
	(wire
		(pts
			(xy 130.81 134.62) (xy 222.25 134.62)
		)
		(stroke
			(width 0)
			(type default)
		)
	)
	(wire
		(pts
			(xy 224.79 168.91) (xy 227.33 168.91)
		)
		(stroke
			(width 0)
			(type default)
		)
	)
	(wire
		(pts
			(xy 241.3 133.35) (xy 273.05 133.35)
		)
		(stroke
			(width 0)
			(type default)
		)
	)
	(wire
		(pts
			(xy 241.3 97.79) (xy 273.05 97.79)
		)
		(stroke
			(width 0)
			(type default)
		)
	)
	(wire
		(pts
			(xy 100.33 151.13) (xy 100.33 153.67)
		)
		(stroke
			(width 0)
			(type default)
		)
	)
	(wire
		(pts
			(xy 102.87 134.62) (xy 106.68 134.62)
		)
		(stroke
			(width 0)
			(type default)
		)
	)
	(wire
		(pts
			(xy 224.79 161.29) (xy 227.33 161.29)
		)
		(stroke
			(width 0)
			(type default)
		)
	)
	(wire
		(pts
			(xy 241.3 194.31) (xy 273.05 194.31)
		)
		(stroke
			(width 0)
			(type default)
		)
	)
	(bus
		(pts
			(xy 276.86 82.55) (xy 278.13 82.55)
		)
		(stroke
			(width 0)
			(type default)
		)
	)
	(wire
		(pts
			(xy 222.25 134.62) (xy 222.25 135.89)
		)
		(stroke
			(width 0)
			(type default)
		)
	)
	(wire
		(pts
			(xy 241.3 189.23) (xy 273.05 189.23)
		)
		(stroke
			(width 0)
			(type default)
		)
	)
	(bus
		(pts
			(xy 275.59 191.77) (xy 275.59 194.31)
		)
		(stroke
			(width 0)
			(type default)
		)
	)
	(wire
		(pts
			(xy 186.69 158.75) (xy 227.33 158.75)
		)
		(stroke
			(width 0)
			(type default)
		)
	)
	(wire
		(pts
			(xy 100.33 142.24) (xy 110.49 142.24)
		)
		(stroke
			(width 0)
			(type default)
		)
	)
	(wire
		(pts
			(xy 105.41 151.13) (xy 100.33 151.13)
		)
		(stroke
			(width 0)
			(type default)
		)
	)
	(bus
		(pts
			(xy 275.59 129.54) (xy 276.86 128.27)
		)
		(stroke
			(width 0)
			(type default)
		)
	)
	(wire
		(pts
			(xy 224.79 107.95) (xy 227.33 107.95)
		)
		(stroke
			(width 0)
			(type default)
		)
	)
	(bus
		(pts
			(xy 275.59 153.67) (xy 275.59 156.21)
		)
		(stroke
			(width 0)
			(type default)
		)
	)
	(wire
		(pts
			(xy 127 123.19) (xy 127 134.62)
		)
		(stroke
			(width 0)
			(type default)
		)
	)
	(wire
		(pts
			(xy 184.15 80.01) (xy 227.33 80.01)
		)
		(stroke
			(width 0)
			(type default)
		)
	)
	(wire
		(pts
			(xy 241.3 123.19) (xy 243.84 123.19)
		)
		(stroke
			(width 0)
			(type default)
		)
	)
	(wire
		(pts
			(xy 241.3 125.73) (xy 273.05 125.73)
		)
		(stroke
			(width 0)
			(type default)
		)
	)
	(bus
		(pts
			(xy 275.59 168.91) (xy 275.59 171.45)
		)
		(stroke
			(width 0)
			(type default)
		)
	)
	(bus
		(pts
			(xy 275.59 83.82) (xy 276.86 82.55)
		)
		(stroke
			(width 0)
			(type default)
		)
	)
	(wire
		(pts
			(xy 243.84 146.05) (xy 243.84 153.67)
		)
		(stroke
			(width 0)
			(type default)
		)
	)
	(wire
		(pts
			(xy 241.3 138.43) (xy 243.84 138.43)
		)
		(stroke
			(width 0)
			(type default)
		)
	)
	(wire
		(pts
			(xy 241.3 184.15) (xy 243.84 184.15)
		)
		(stroke
			(width 0)
			(type default)
		)
	)
	(bus
		(pts
			(xy 181.61 118.11) (xy 181.61 123.19)
		)
		(stroke
			(width 0)
			(type default)
		)
	)
	(wire
		(pts
			(xy 241.3 118.11) (xy 273.05 118.11)
		)
		(stroke
			(width 0)
			(type default)
		)
	)
	(wire
		(pts
			(xy 243.84 85.09) (xy 243.84 92.71)
		)
		(stroke
			(width 0)
			(type default)
		)
	)
	(bus
		(pts
			(xy 275.59 106.68) (xy 275.59 107.95)
		)
		(stroke
			(width 0)
			(type default)
		)
	)
	(wire
		(pts
			(xy 243.84 204.47) (xy 243.84 208.28)
		)
		(stroke
			(width 0)
			(type default)
		)
	)
	(wire
		(pts
			(xy 186.69 189.23) (xy 227.33 189.23)
		)
		(stroke
			(width 0)
			(type default)
		)
	)
	(wire
		(pts
			(xy 224.79 153.67) (xy 227.33 153.67)
		)
		(stroke
			(width 0)
			(type default)
		)
	)
	(bus
		(pts
			(xy 275.59 115.57) (xy 275.59 118.11)
		)
		(stroke
			(width 0)
			(type default)
		)
	)
	(bus
		(pts
			(xy 275.59 95.25) (xy 275.59 100.33)
		)
		(stroke
			(width 0)
			(type default)
		)
	)
	(wire
		(pts
			(xy 241.3 135.89) (xy 273.05 135.89)
		)
		(stroke
			(width 0)
			(type default)
		)
	)
	(wire
		(pts
			(xy 224.79 199.39) (xy 227.33 199.39)
		)
		(stroke
			(width 0)
			(type default)
		)
	)
	(bus
		(pts
			(xy 275.59 100.33) (xy 275.59 102.87)
		)
		(stroke
			(width 0)
			(type default)
		)
	)
	(bus
		(pts
			(xy 181.61 115.57) (xy 181.61 118.11)
		)
		(stroke
			(width 0)
			(type default)
		)
	)
	(bus
		(pts
			(xy 275.59 160.02) (xy 276.86 158.75)
		)
		(stroke
			(width 0)
			(type default)
		)
	)
	(wire
		(pts
			(xy 224.79 123.19) (xy 224.79 146.05)
		)
		(stroke
			(width 0)
			(type default)
		)
	)
	(wire
		(pts
			(xy 241.3 95.25) (xy 273.05 95.25)
		)
		(stroke
			(width 0)
			(type default)
		)
	)
	(wire
		(pts
			(xy 241.3 143.51) (xy 273.05 143.51)
		)
		(stroke
			(width 0)
			(type default)
		)
	)
	(wire
		(pts
			(xy 224.79 199.39) (xy 224.79 208.28)
		)
		(stroke
			(width 0)
			(type default)
		)
	)
	(bus
		(pts
			(xy 184.15 171.45) (xy 184.15 176.53)
		)
		(stroke
			(width 0)
			(type default)
		)
	)
	(bus
		(pts
			(xy 275.59 123.19) (xy 275.59 125.73)
		)
		(stroke
			(width 0)
			(type default)
		)
	)
	(bus
		(pts
			(xy 181.61 196.85) (xy 182.88 196.85)
		)
		(stroke
			(width 0)
			(type default)
		)
	)
	(wire
		(pts
			(xy 224.79 184.15) (xy 224.79 191.77)
		)
		(stroke
			(width 0)
			(type default)
		)
	)
	(wire
		(pts
			(xy 241.3 176.53) (xy 243.84 176.53)
		)
		(stroke
			(width 0)
			(type default)
		)
	)
	(wire
		(pts
			(xy 241.3 100.33) (xy 243.84 100.33)
		)
		(stroke
			(width 0)
			(type default)
		)
	)
	(wire
		(pts
			(xy 186.69 179.07) (xy 227.33 179.07)
		)
		(stroke
			(width 0)
			(type default)
		)
	)
	(wire
		(pts
			(xy 241.3 115.57) (xy 243.84 115.57)
		)
		(stroke
			(width 0)
			(type default)
		)
	)
	(bus
		(pts
			(xy 181.61 76.2) (xy 181.61 77.47)
		)
		(stroke
			(width 0)
			(type default)
		)
	)
	(wire
		(pts
			(xy 224.79 92.71) (xy 227.33 92.71)
		)
		(stroke
			(width 0)
			(type default)
		)
	)
	(wire
		(pts
			(xy 184.15 95.25) (xy 227.33 95.25)
		)
		(stroke
			(width 0)
			(type default)
		)
	)
	(wire
		(pts
			(xy 184.15 113.03) (xy 227.33 113.03)
		)
		(stroke
			(width 0)
			(type default)
		)
	)
	(wire
		(pts
			(xy 125.73 134.62) (xy 127 134.62)
		)
		(stroke
			(width 0)
			(type default)
		)
	)
	(wire
		(pts
			(xy 243.84 191.77) (xy 243.84 199.39)
		)
		(stroke
			(width 0)
			(type default)
		)
	)
	(bus
		(pts
			(xy 181.61 92.71) (xy 181.61 95.25)
		)
		(stroke
			(width 0)
			(type default)
		)
	)
	(wire
		(pts
			(xy 224.79 191.77) (xy 227.33 191.77)
		)
		(stroke
			(width 0)
			(type default)
		)
	)
	(bus
		(pts
			(xy 275.59 184.15) (xy 275.59 186.69)
		)
		(stroke
			(width 0)
			(type default)
		)
	)
	(wire
		(pts
			(xy 186.69 171.45) (xy 227.33 171.45)
		)
		(stroke
			(width 0)
			(type default)
		)
	)
	(wire
		(pts
			(xy 241.3 196.85) (xy 273.05 196.85)
		)
		(stroke
			(width 0)
			(type default)
		)
	)
	(wire
		(pts
			(xy 241.3 168.91) (xy 243.84 168.91)
		)
		(stroke
			(width 0)
			(type default)
		)
	)
	(wire
		(pts
			(xy 184.15 120.65) (xy 227.33 120.65)
		)
		(stroke
			(width 0)
			(type default)
		)
	)
	(wire
		(pts
			(xy 227.33 85.09) (xy 224.79 85.09)
		)
		(stroke
			(width 0)
			(type default)
		)
	)
	(bus
		(pts
			(xy 184.15 148.59) (xy 184.15 153.67)
		)
		(stroke
			(width 0)
			(type default)
		)
	)
	(wire
		(pts
			(xy 241.3 163.83) (xy 273.05 163.83)
		)
		(stroke
			(width 0)
			(type default)
		)
	)
	(wire
		(pts
			(xy 241.3 161.29) (xy 243.84 161.29)
		)
		(stroke
			(width 0)
			(type default)
		)
	)
	(bus
		(pts
			(xy 181.61 95.25) (xy 181.61 100.33)
		)
		(stroke
			(width 0)
			(type default)
		)
	)
	(wire
		(pts
			(xy 186.69 194.31) (xy 227.33 194.31)
		)
		(stroke
			(width 0)
			(type default)
		)
	)
	(wire
		(pts
			(xy 243.84 199.39) (xy 243.84 204.47)
		)
		(stroke
			(width 0)
			(type default)
		)
	)
	(wire
		(pts
			(xy 186.69 181.61) (xy 227.33 181.61)
		)
		(stroke
			(width 0)
			(type default)
		)
	)
	(bus
		(pts
			(xy 275.59 92.71) (xy 275.59 95.25)
		)
		(stroke
			(width 0)
			(type default)
		)
	)
	(bus
		(pts
			(xy 275.59 133.35) (xy 275.59 138.43)
		)
		(stroke
			(width 0)
			(type default)
		)
	)
	(bus
		(pts
			(xy 275.59 161.29) (xy 275.59 163.83)
		)
		(stroke
			(width 0)
			(type default)
		)
	)
	(wire
		(pts
			(xy 224.79 85.09) (xy 224.79 92.71)
		)
		(stroke
			(width 0)
			(type default)
		)
	)
	(bus
		(pts
			(xy 276.86 196.85) (xy 278.13 196.85)
		)
		(stroke
			(width 0)
			(type default)
		)
	)
	(wire
		(pts
			(xy 241.3 130.81) (xy 243.84 130.81)
		)
		(stroke
			(width 0)
			(type default)
		)
	)
	(wire
		(pts
			(xy 241.3 77.47) (xy 243.84 77.47)
		)
		(stroke
			(width 0)
			(type default)
		)
	)
	(wire
		(pts
			(xy 243.84 161.29) (xy 243.84 168.91)
		)
		(stroke
			(width 0)
			(type default)
		)
	)
	(wire
		(pts
			(xy 243.84 153.67) (xy 243.84 161.29)
		)
		(stroke
			(width 0)
			(type default)
		)
	)
	(bus
		(pts
			(xy 181.61 77.47) (xy 181.61 80.01)
		)
		(stroke
			(width 0)
			(type default)
		)
	)
	(bus
		(pts
			(xy 275.59 179.07) (xy 275.59 184.15)
		)
		(stroke
			(width 0)
			(type default)
		)
	)
	(wire
		(pts
			(xy 222.25 140.97) (xy 227.33 140.97)
		)
		(stroke
			(width 0)
			(type default)
		)
	)
	(bus
		(pts
			(xy 275.59 198.12) (xy 275.59 199.39)
		)
		(stroke
			(width 0)
			(type default)
		)
	)
	(wire
		(pts
			(xy 243.84 168.91) (xy 243.84 176.53)
		)
		(stroke
			(width 0)
			(type default)
		)
	)
	(wire
		(pts
			(xy 243.84 176.53) (xy 243.84 184.15)
		)
		(stroke
			(width 0)
			(type default)
		)
	)
	(wire
		(pts
			(xy 100.33 158.75) (xy 100.33 160.02)
		)
		(stroke
			(width 0)
			(type default)
		)
	)
	(bus
		(pts
			(xy 182.88 166.37) (xy 184.15 167.64)
		)
		(stroke
			(width 0)
			(type default)
		)
	)
	(bus
		(pts
			(xy 275.59 83.82) (xy 275.59 85.09)
		)
		(stroke
			(width 0)
			(type default)
		)
	)
	(wire
		(pts
			(xy 241.3 120.65) (xy 273.05 120.65)
		)
		(stroke
			(width 0)
			(type default)
		)
	)
	(wire
		(pts
			(xy 241.3 179.07) (xy 273.05 179.07)
		)
		(stroke
			(width 0)
			(type default)
		)
	)
	(wire
		(pts
			(xy 224.79 176.53) (xy 227.33 176.53)
		)
		(stroke
			(width 0)
			(type default)
		)
	)
	(wire
		(pts
			(xy 119.38 134.62) (xy 125.73 134.62)
		)
		(stroke
			(width 0)
			(type default)
		)
	)
	(bus
		(pts
			(xy 184.15 146.05) (xy 184.15 148.59)
		)
		(stroke
			(width 0)
			(type default)
		)
	)
	(bus
		(pts
			(xy 275.59 129.54) (xy 275.59 130.81)
		)
		(stroke
			(width 0)
			(type default)
		)
	)
	(wire
		(pts
			(xy 241.3 199.39) (xy 243.84 199.39)
		)
		(stroke
			(width 0)
			(type default)
		)
	)
	(wire
		(pts
			(xy 241.3 153.67) (xy 243.84 153.67)
		)
		(stroke
			(width 0)
			(type default)
		)
	)
	(bus
		(pts
			(xy 275.59 176.53) (xy 275.59 179.07)
		)
		(stroke
			(width 0)
			(type default)
		)
	)
	(bus
		(pts
			(xy 275.59 107.95) (xy 275.59 110.49)
		)
		(stroke
			(width 0)
			(type default)
		)
	)
	(bus
		(pts
			(xy 275.59 190.5) (xy 275.59 191.77)
		)
		(stroke
			(width 0)
			(type default)
		)
	)
	(bus
		(pts
			(xy 182.88 143.51) (xy 184.15 144.78)
		)
		(stroke
			(width 0)
			(type default)
		)
	)
	(wire
		(pts
			(xy 241.3 110.49) (xy 273.05 110.49)
		)
		(stroke
			(width 0)
			(type default)
		)
	)
	(wire
		(pts
			(xy 125.73 148.59) (xy 125.73 134.62)
		)
		(stroke
			(width 0)
			(type default)
		)
	)
	(wire
		(pts
			(xy 121.92 148.59) (xy 125.73 148.59)
		)
		(stroke
			(width 0)
			(type default)
		)
	)
	(wire
		(pts
			(xy 224.79 191.77) (xy 224.79 199.39)
		)
		(stroke
			(width 0)
			(type default)
		)
	)
	(bus
		(pts
			(xy 275.59 138.43) (xy 275.59 140.97)
		)
		(stroke
			(width 0)
			(type default)
		)
	)
	(bus
		(pts
			(xy 184.15 176.53) (xy 184.15 179.07)
		)
		(stroke
			(width 0)
			(type default)
		)
	)
	(wire
		(pts
			(xy 222.25 133.35) (xy 222.25 134.62)
		)
		(stroke
			(width 0)
			(type default)
		)
	)
	(bus
		(pts
			(xy 180.34 90.17) (xy 181.61 91.44)
		)
		(stroke
			(width 0)
			(type default)
		)
	)
	(wire
		(pts
			(xy 184.15 82.55) (xy 227.33 82.55)
		)
		(stroke
			(width 0)
			(type default)
		)
	)
	(wire
		(pts
			(xy 101.6 134.62) (xy 102.87 134.62)
		)
		(stroke
			(width 0)
			(type default)
		)
	)
	(bus
		(pts
			(xy 276.86 189.23) (xy 278.13 189.23)
		)
		(stroke
			(width 0)
			(type default)
		)
	)
	(wire
		(pts
			(xy 184.15 125.73) (xy 227.33 125.73)
		)
		(stroke
			(width 0)
			(type default)
		)
	)
	(wire
		(pts
			(xy 241.3 113.03) (xy 273.05 113.03)
		)
		(stroke
			(width 0)
			(type default)
		)
	)
	(wire
		(pts
			(xy 243.84 184.15) (xy 243.84 191.77)
		)
		(stroke
			(width 0)
			(type default)
		)
	)
	(bus
		(pts
			(xy 275.59 160.02) (xy 275.59 161.29)
		)
		(stroke
			(width 0)
			(type default)
		)
	)
	(wire
		(pts
			(xy 222.25 143.51) (xy 227.33 143.51)
		)
		(stroke
			(width 0)
			(type default)
		)
	)
	(bus
		(pts
			(xy 275.59 171.45) (xy 275.59 176.53)
		)
		(stroke
			(width 0)
			(type default)
		)
	)
	(wire
		(pts
			(xy 241.3 151.13) (xy 273.05 151.13)
		)
		(stroke
			(width 0)
			(type default)
		)
	)
	(bus
		(pts
			(xy 275.59 163.83) (xy 275.59 168.91)
		)
		(stroke
			(width 0)
			(type default)
		)
	)
	(bus
		(pts
			(xy 275.59 198.12) (xy 276.86 196.85)
		)
		(stroke
			(width 0)
			(type default)
		)
	)
	(bus
		(pts
			(xy 179.07 74.93) (xy 180.34 74.93)
		)
		(stroke
			(width 0)
			(type default)
		)
	)
	(bus
		(pts
			(xy 275.59 148.59) (xy 275.59 153.67)
		)
		(stroke
			(width 0)
			(type default)
		)
	)
	(wire
		(pts
			(xy 224.79 153.67) (xy 224.79 161.29)
		)
		(stroke
			(width 0)
			(type default)
		)
	)
	(wire
		(pts
			(xy 96.52 134.62) (xy 101.6 134.62)
		)
		(stroke
			(width 0)
			(type default)
		)
	)
	(wire
		(pts
			(xy 243.84 107.95) (xy 243.84 115.57)
		)
		(stroke
			(width 0)
			(type default)
		)
	)
	(bus
		(pts
			(xy 181.61 76.2) (xy 180.34 74.93)
		)
		(stroke
			(width 0)
			(type default)
		)
	)
	(wire
		(pts
			(xy 102.87 148.59) (xy 102.87 134.62)
		)
		(stroke
			(width 0)
			(type default)
		)
	)
	(wire
		(pts
			(xy 243.84 138.43) (xy 243.84 146.05)
		)
		(stroke
			(width 0)
			(type default)
		)
	)
	(bus
		(pts
			(xy 181.61 123.19) (xy 181.61 125.73)
		)
		(stroke
			(width 0)
			(type default)
		)
	)
	(bus
		(pts
			(xy 275.59 130.81) (xy 275.59 133.35)
		)
		(stroke
			(width 0)
			(type default)
		)
	)
	(wire
		(pts
			(xy 241.3 87.63) (xy 273.05 87.63)
		)
		(stroke
			(width 0)
			(type default)
		)
	)
	(wire
		(pts
			(xy 222.25 87.63) (xy 227.33 87.63)
		)
		(stroke
			(width 0)
			(type default)
		)
	)
	(wire
		(pts
			(xy 121.92 151.13) (xy 123.19 151.13)
		)
		(stroke
			(width 0)
			(type default)
		)
	)
	(bus
		(pts
			(xy 184.15 144.78) (xy 184.15 146.05)
		)
		(stroke
			(width 0)
			(type default)
		)
	)
	(wire
		(pts
			(xy 186.69 196.85) (xy 227.33 196.85)
		)
		(stroke
			(width 0)
			(type default)
		)
	)
	(bus
		(pts
			(xy 184.15 198.12) (xy 184.15 199.39)
		)
		(stroke
			(width 0)
			(type default)
		)
	)
	(wire
		(pts
			(xy 186.69 148.59) (xy 227.33 148.59)
		)
		(stroke
			(width 0)
			(type default)
		)
	)
	(wire
		(pts
			(xy 224.79 92.71) (xy 224.79 100.33)
		)
		(stroke
			(width 0)
			(type default)
		)
	)
	(bus
		(pts
			(xy 181.61 110.49) (xy 181.61 115.57)
		)
		(stroke
			(width 0)
			(type default)
		)
	)
	(bus
		(pts
			(xy 275.59 140.97) (xy 275.59 146.05)
		)
		(stroke
			(width 0)
			(type default)
		)
	)
	(wire
		(pts
			(xy 241.3 186.69) (xy 273.05 186.69)
		)
		(stroke
			(width 0)
			(type default)
		)
	)
	(wire
		(pts
			(xy 186.69 156.21) (xy 227.33 156.21)
		)
		(stroke
			(width 0)
			(type default)
		)
	)
	(bus
		(pts
			(xy 275.59 146.05) (xy 275.59 148.59)
		)
		(stroke
			(width 0)
			(type default)
		)
	)
	(wire
		(pts
			(xy 110.49 123.19) (xy 101.6 123.19)
		)
		(stroke
			(width 0)
			(type default)
		)
	)
	(wire
		(pts
			(xy 184.15 102.87) (xy 227.33 102.87)
		)
		(stroke
			(width 0)
			(type default)
		)
	)
	(bus
		(pts
			(xy 181.61 91.44) (xy 181.61 92.71)
		)
		(stroke
			(width 0)
			(type default)
		)
	)
	(wire
		(pts
			(xy 224.79 168.91) (xy 224.79 176.53)
		)
		(stroke
			(width 0)
			(type default)
		)
	)
	(wire
		(pts
			(xy 241.3 102.87) (xy 273.05 102.87)
		)
		(stroke
			(width 0)
			(type default)
		)
	)
	(wire
		(pts
			(xy 241.3 171.45) (xy 273.05 171.45)
		)
		(stroke
			(width 0)
			(type default)
		)
	)
	(wire
		(pts
			(xy 186.69 151.13) (xy 227.33 151.13)
		)
		(stroke
			(width 0)
			(type default)
		)
	)
	(bus
		(pts
			(xy 184.15 186.69) (xy 184.15 191.77)
		)
		(stroke
			(width 0)
			(type default)
		)
	)
	(wire
		(pts
			(xy 101.6 123.19) (xy 101.6 134.62)
		)
		(stroke
			(width 0)
			(type default)
		)
	)
	(wire
		(pts
			(xy 222.25 135.89) (xy 227.33 135.89)
		)
		(stroke
			(width 0)
			(type default)
		)
	)
	(wire
		(pts
			(xy 241.3 158.75) (xy 273.05 158.75)
		)
		(stroke
			(width 0)
			(type default)
		)
	)
	(wire
		(pts
			(xy 115.57 123.19) (xy 127 123.19)
		)
		(stroke
			(width 0)
			(type default)
		)
	)
	(bus
		(pts
			(xy 179.07 90.17) (xy 180.34 90.17)
		)
		(stroke
			(width 0)
			(type default)
		)
	)
	(wire
		(pts
			(xy 241.3 140.97) (xy 273.05 140.97)
		)
		(stroke
			(width 0)
			(type default)
		)
	)
	(wire
		(pts
			(xy 224.79 115.57) (xy 227.33 115.57)
		)
		(stroke
			(width 0)
			(type default)
		)
	)
	(wire
		(pts
			(xy 184.15 118.11) (xy 227.33 118.11)
		)
		(stroke
			(width 0)
			(type default)
		)
	)
	(wire
		(pts
			(xy 241.3 191.77) (xy 243.84 191.77)
		)
		(stroke
			(width 0)
			(type default)
		)
	)
	(bus
		(pts
			(xy 184.15 191.77) (xy 184.15 194.31)
		)
		(stroke
			(width 0)
			(type default)
		)
	)
	(wire
		(pts
			(xy 186.69 173.99) (xy 227.33 173.99)
		)
		(stroke
			(width 0)
			(type default)
		)
	)
	(wire
		(pts
			(xy 123.19 158.75) (xy 123.19 160.02)
		)
		(stroke
			(width 0)
			(type default)
		)
	)
	(wire
		(pts
			(xy 241.3 92.71) (xy 243.84 92.71)
		)
		(stroke
			(width 0)
			(type default)
		)
	)
	(wire
		(pts
			(xy 243.84 115.57) (xy 243.84 123.19)
		)
		(stroke
			(width 0)
			(type default)
		)
	)
	(wire
		(pts
			(xy 184.15 128.27) (xy 227.33 128.27)
		)
		(stroke
			(width 0)
			(type default)
		)
	)
	(wire
		(pts
			(xy 130.81 133.35) (xy 130.81 134.62)
		)
		(stroke
			(width 0)
			(type default)
		)
	)
	(wire
		(pts
			(xy 241.3 148.59) (xy 273.05 148.59)
		)
		(stroke
			(width 0)
			(type default)
		)
	)
	(wire
		(pts
			(xy 224.79 100.33) (xy 227.33 100.33)
		)
		(stroke
			(width 0)
			(type default)
		)
	)
	(wire
		(pts
			(xy 241.3 107.95) (xy 243.84 107.95)
		)
		(stroke
			(width 0)
			(type default)
		)
	)
	(wire
		(pts
			(xy 241.3 105.41) (xy 273.05 105.41)
		)
		(stroke
			(width 0)
			(type default)
		)
	)
	(bus
		(pts
			(xy 276.86 128.27) (xy 278.13 128.27)
		)
		(stroke
			(width 0)
			(type default)
		)
	)
	(wire
		(pts
			(xy 123.19 151.13) (xy 123.19 153.67)
		)
		(stroke
			(width 0)
			(type default)
		)
	)
	(wire
		(pts
			(xy 105.41 148.59) (xy 102.87 148.59)
		)
		(stroke
			(width 0)
			(type default)
		)
	)
	(wire
		(pts
			(xy 224.79 176.53) (xy 224.79 184.15)
		)
		(stroke
			(width 0)
			(type default)
		)
	)
	(bus
		(pts
			(xy 275.59 110.49) (xy 275.59 115.57)
		)
		(stroke
			(width 0)
			(type default)
		)
	)
	(wire
		(pts
			(xy 184.15 105.41) (xy 227.33 105.41)
		)
		(stroke
			(width 0)
			(type default)
		)
	)
	(wire
		(pts
			(xy 222.25 138.43) (xy 227.33 138.43)
		)
		(stroke
			(width 0)
			(type default)
		)
	)
	(wire
		(pts
			(xy 241.3 204.47) (xy 243.84 204.47)
		)
		(stroke
			(width 0)
			(type default)
		)
	)
	(wire
		(pts
			(xy 224.79 184.15) (xy 227.33 184.15)
		)
		(stroke
			(width 0)
			(type default)
		)
	)
	(wire
		(pts
			(xy 243.84 130.81) (xy 243.84 138.43)
		)
		(stroke
			(width 0)
			(type default)
		)
	)
	(wire
		(pts
			(xy 243.84 100.33) (xy 243.84 107.95)
		)
		(stroke
			(width 0)
			(type default)
		)
	)
	(wire
		(pts
			(xy 184.15 97.79) (xy 227.33 97.79)
		)
		(stroke
			(width 0)
			(type default)
		)
	)
	(bus
		(pts
			(xy 276.86 105.41) (xy 278.13 105.41)
		)
		(stroke
			(width 0)
			(type default)
		)
	)
	(wire
		(pts
			(xy 241.3 181.61) (xy 273.05 181.61)
		)
		(stroke
			(width 0)
			(type default)
		)
	)
	(wire
		(pts
			(xy 224.79 161.29) (xy 224.79 168.91)
		)
		(stroke
			(width 0)
			(type default)
		)
	)
	(wire
		(pts
			(xy 241.3 166.37) (xy 273.05 166.37)
		)
		(stroke
			(width 0)
			(type default)
		)
	)
	(bus
		(pts
			(xy 182.88 196.85) (xy 184.15 198.12)
		)
		(stroke
			(width 0)
			(type default)
		)
	)
	(bus
		(pts
			(xy 275.59 118.11) (xy 275.59 123.19)
		)
		(stroke
			(width 0)
			(type default)
		)
	)
	(wire
		(pts
			(xy 241.3 90.17) (xy 273.05 90.17)
		)
		(stroke
			(width 0)
			(type default)
		)
	)
	(wire
		(pts
			(xy 241.3 156.21) (xy 273.05 156.21)
		)
		(stroke
			(width 0)
			(type default)
		)
	)
	(wire
		(pts
			(xy 241.3 201.93) (xy 273.05 201.93)
		)
		(stroke
			(width 0)
			(type default)
		)
	)
	(wire
		(pts
			(xy 222.25 135.89) (xy 222.25 138.43)
		)
		(stroke
			(width 0)
			(type default)
		)
	)
	(wire
		(pts
			(xy 224.79 107.95) (xy 224.79 115.57)
		)
		(stroke
			(width 0)
			(type default)
		)
	)
	(bus
		(pts
			(xy 184.15 167.64) (xy 184.15 168.91)
		)
		(stroke
			(width 0)
			(type default)
		)
	)
	(wire
		(pts
			(xy 222.25 77.47) (xy 227.33 77.47)
		)
		(stroke
			(width 0)
			(type default)
		)
	)
	(bus
		(pts
			(xy 181.61 100.33) (xy 181.61 102.87)
		)
		(stroke
			(width 0)
			(type default)
		)
	)
	(bus
		(pts
			(xy 275.59 190.5) (xy 276.86 189.23)
		)
		(stroke
			(width 0)
			(type default)
		)
	)
	(wire
		(pts
			(xy 222.25 130.81) (xy 222.25 133.35)
		)
		(stroke
			(width 0)
			(type default)
		)
	)
	(wire
		(pts
			(xy 224.79 146.05) (xy 227.33 146.05)
		)
		(stroke
			(width 0)
			(type default)
		)
	)
	(bus
		(pts
			(xy 181.61 166.37) (xy 182.88 166.37)
		)
		(stroke
			(width 0)
			(type default)
		)
	)
	(wire
		(pts
			(xy 224.79 115.57) (xy 224.79 123.19)
		)
		(stroke
			(width 0)
			(type default)
		)
	)
	(wire
		(pts
			(xy 224.79 123.19) (xy 227.33 123.19)
		)
		(stroke
			(width 0)
			(type default)
		)
	)
	(bus
		(pts
			(xy 184.15 153.67) (xy 184.15 156.21)
		)
		(stroke
			(width 0)
			(type default)
		)
	)
	(bus
		(pts
			(xy 275.59 106.68) (xy 276.86 105.41)
		)
		(stroke
			(width 0)
			(type default)
		)
	)
	(bus
		(pts
			(xy 184.15 179.07) (xy 184.15 184.15)
		)
		(stroke
			(width 0)
			(type default)
		)
	)
	(wire
		(pts
			(xy 100.33 151.13) (xy 100.33 142.24)
		)
		(stroke
			(width 0)
			(type default)
		)
	)
	(wire
		(pts
			(xy 186.69 186.69) (xy 227.33 186.69)
		)
		(stroke
			(width 0)
			(type default)
		)
	)
	(bus
		(pts
			(xy 184.15 184.15) (xy 184.15 186.69)
		)
		(stroke
			(width 0)
			(type default)
		)
	)
	(label "CAM0.C_P"
		(at 271.78 128.27 180)
		(effects
			(font
				(size 1.27 1.27)
			)
			(justify right bottom)
		)
	)
	(label "CONN.D_P"
		(at 196.85 82.55 180)
		(effects
			(font
				(size 1.27 1.27)
			)
			(justify right bottom)
		)
	)
	(label "CAM1.D2_P"
		(at 186.055 120.65 0)
		(effects
			(font
				(size 1.27 1.27)
			)
			(justify left bottom)
		)
	)
	(label "HDMI0.SCL"
		(at 272.415 201.93 180)
		(effects
			(font
				(size 1.27 1.27)
			)
			(justify right bottom)
		)
	)
	(label "CAM1.C_N"
		(at 186.055 110.49 0)
		(effects
			(font
				(size 1.27 1.27)
			)
			(justify left bottom)
		)
	)
	(label "PCIE.RXD1_N"
		(at 272.415 143.51 180)
		(effects
			(font
				(size 1.27 1.27)
			)
			(justify right bottom)
		)
	)
	(label "PCIE.TXD3_N"
		(at 186.69 156.21 0)
		(effects
			(font
				(size 1.27 1.27)
			)
			(justify left bottom)
		)
	)
	(label "PCIE.TXD2_N"
		(at 272.415 151.13 180)
		(effects
			(font
				(size 1.27 1.27)
			)
			(justify right bottom)
		)
	)
	(label "CAM1.C_P"
		(at 186.055 113.03 0)
		(effects
			(font
				(size 1.27 1.27)
			)
			(justify left bottom)
		)
	)
	(label "CAM0.D0_N"
		(at 271.78 110.49 180)
		(effects
			(font
				(size 1.27 1.27)
			)
			(justify right bottom)
		)
	)
	(label "HDMI0.SDA"
		(at 222.25 201.93 180)
		(effects
			(font
				(size 1.27 1.27)
			)
			(justify right bottom)
		)
	)
	(label "DSI1.D0_P"
		(at 187.96 173.99 0)
		(effects
			(font
				(size 1.27 1.27)
			)
			(justify left bottom)
		)
	)
	(label "PCIE.TXD1_P"
		(at 272.415 133.35 180)
		(effects
			(font
				(size 1.27 1.27)
			)
			(justify right bottom)
		)
	)
	(label "CAM1.D0_N"
		(at 186.055 95.25 0)
		(effects
			(font
				(size 1.27 1.27)
			)
			(justify left bottom)
		)
	)
	(label "PCIE.TXD3_P"
		(at 186.69 158.75 0)
		(effects
			(font
				(size 1.27 1.27)
			)
			(justify left bottom)
		)
	)
	(label "HDMI0.CLK_N"
		(at 272.415 189.23 180)
		(effects
			(font
				(size 1.27 1.27)
			)
			(justify right bottom)
		)
	)
	(label "DSI1.C_N"
		(at 187.96 186.69 0)
		(effects
			(font
				(size 1.27 1.27)
			)
			(justify left bottom)
		)
	)
	(label "CAM1.D3_N"
		(at 186.055 125.73 0)
		(effects
			(font
				(size 1.27 1.27)
			)
			(justify left bottom)
		)
	)
	(label "DSI1.D2_P"
		(at 187.96 196.85 0)
		(effects
			(font
				(size 1.27 1.27)
			)
			(justify left bottom)
		)
	)
	(label "PCIE.RXD1_P"
		(at 272.415 140.97 180)
		(effects
			(font
				(size 1.27 1.27)
			)
			(justify right bottom)
		)
	)
	(label "HDMI0.TX2_N"
		(at 272.415 166.37 180)
		(effects
			(font
				(size 1.27 1.27)
			)
			(justify right bottom)
		)
	)
	(label "CAM1.D0_P"
		(at 186.055 97.79 0)
		(effects
			(font
				(size 1.27 1.27)
			)
			(justify left bottom)
		)
	)
	(label "DSI1.D1_N"
		(at 187.96 179.07 0)
		(effects
			(font
				(size 1.27 1.27)
			)
			(justify left bottom)
		)
	)
	(label "CAM0.D1_N"
		(at 271.78 118.11 180)
		(effects
			(font
				(size 1.27 1.27)
			)
			(justify right bottom)
		)
	)
	(label "DSI1.D2_N"
		(at 187.96 194.31 0)
		(effects
			(font
				(size 1.27 1.27)
			)
			(justify left bottom)
		)
	)
	(label "PCIE.RXD2_P"
		(at 186.69 151.13 0)
		(effects
			(font
				(size 1.27 1.27)
			)
			(justify left bottom)
		)
	)
	(label "PCIE.CLK_P"
		(at 272.415 87.63 180)
		(effects
			(font
				(size 1.27 1.27)
			)
			(justify right bottom)
		)
	)
	(label "HDMI0.CLK_P"
		(at 272.415 186.69 180)
		(effects
			(font
				(size 1.27 1.27)
			)
			(justify right bottom)
		)
	)
	(label "DSI1.C_P"
		(at 187.96 189.23 0)
		(effects
			(font
				(size 1.27 1.27)
			)
			(justify left bottom)
		)
	)
	(label "PCIE.TXD0_P"
		(at 272.415 102.87 180)
		(effects
			(font
				(size 1.27 1.27)
			)
			(justify right bottom)
		)
	)
	(label "DSI1.D3_P"
		(at 271.145 196.85 180)
		(effects
			(font
				(size 1.27 1.27)
			)
			(justify right bottom)
		)
	)
	(label "CAM1.D3_P"
		(at 186.055 128.27 0)
		(effects
			(font
				(size 1.27 1.27)
			)
			(justify left bottom)
		)
	)
	(label "HDMI0.TX0_N"
		(at 272.415 181.61 180)
		(effects
			(font
				(size 1.27 1.27)
			)
			(justify right bottom)
		)
	)
	(label "CAM0.D0_P"
		(at 271.78 113.03 180)
		(effects
			(font
				(size 1.27 1.27)
			)
			(justify right bottom)
		)
	)
	(label "HDMI0.TX0_P"
		(at 272.415 179.07 180)
		(effects
			(font
				(size 1.27 1.27)
			)
			(justify right bottom)
		)
	)
	(label "PCIE.RXD3_N"
		(at 272.415 158.75 180)
		(effects
			(font
				(size 1.27 1.27)
			)
			(justify right bottom)
		)
	)
	(label "PCIE.TXD0_N"
		(at 272.415 105.41 180)
		(effects
			(font
				(size 1.27 1.27)
			)
			(justify right bottom)
		)
	)
	(label "CAM1.D1_P"
		(at 186.055 105.41 0)
		(effects
			(font
				(size 1.27 1.27)
			)
			(justify left bottom)
		)
	)
	(label "CAM0.C_N"
		(at 271.78 125.73 180)
		(effects
			(font
				(size 1.27 1.27)
			)
			(justify right bottom)
		)
	)
	(label "HDMI0.TX2_P"
		(at 272.415 163.83 180)
		(effects
			(font
				(size 1.27 1.27)
			)
			(justify right bottom)
		)
	)
	(label "HDMI0.TX1_P"
		(at 272.415 171.45 180)
		(effects
			(font
				(size 1.27 1.27)
			)
			(justify right bottom)
		)
	)
	(label "PCIE.TXD1_N"
		(at 272.415 135.89 180)
		(effects
			(font
				(size 1.27 1.27)
			)
			(justify right bottom)
		)
	)
	(label "CONN.D_N"
		(at 196.85 80.01 180)
		(effects
			(font
				(size 1.27 1.27)
			)
			(justify right bottom)
		)
	)
	(label "PCIE.RXD2_N"
		(at 186.69 148.59 0)
		(effects
			(font
				(size 1.27 1.27)
			)
			(justify left bottom)
		)
	)
	(label "PCIE.TXD2_P"
		(at 272.415 148.59 180)
		(effects
			(font
				(size 1.27 1.27)
			)
			(justify right bottom)
		)
	)
	(label "PCIE.RXD0_N"
		(at 272.415 97.79 180)
		(effects
			(font
				(size 1.27 1.27)
			)
			(justify right bottom)
		)
	)
	(label "PCIE.CLK_N"
		(at 272.415 90.17 180)
		(effects
			(font
				(size 1.27 1.27)
			)
			(justify right bottom)
		)
	)
	(label "HDMI0.TX1_N"
		(at 272.415 173.99 180)
		(effects
			(font
				(size 1.27 1.27)
			)
			(justify right bottom)
		)
	)
	(label "PCIE.RXD0_P"
		(at 272.415 95.25 180)
		(effects
			(font
				(size 1.27 1.27)
			)
			(justify right bottom)
		)
	)
	(label "CAM1.D1_N"
		(at 186.055 102.87 0)
		(effects
			(font
				(size 1.27 1.27)
			)
			(justify left bottom)
		)
	)
	(label "DSI1.D0_N"
		(at 187.96 171.45 0)
		(effects
			(font
				(size 1.27 1.27)
			)
			(justify left bottom)
		)
	)
	(label "DSI1.D3_N"
		(at 271.145 194.31 180)
		(effects
			(font
				(size 1.27 1.27)
			)
			(justify right bottom)
		)
	)
	(label "CAM0.D1_P"
		(at 271.78 120.65 180)
		(effects
			(font
				(size 1.27 1.27)
			)
			(justify right bottom)
		)
	)
	(label "DSI1.D1_P"
		(at 187.96 181.61 0)
		(effects
			(font
				(size 1.27 1.27)
			)
			(justify left bottom)
		)
	)
	(label "PCIE.RXD3_P"
		(at 272.415 156.21 180)
		(effects
			(font
				(size 1.27 1.27)
			)
			(justify right bottom)
		)
	)
	(label "CAM1.D2_N"
		(at 186.055 118.11 0)
		(effects
			(font
				(size 1.27 1.27)
			)
			(justify left bottom)
		)
	)
	(global_label "PCIe_nRST"
		(shape input)
		(at 222.25 87.63 180)
		(fields_autoplaced yes)
		(effects
			(font
				(size 1.27 1.27)
			)
			(justify right)
		)
		(property "Intersheetrefs" "${INTERSHEET_REFS}"
			(at 209.4677 87.63 0)
			(effects
				(font
					(size 1.27 1.27)
				)
				(justify right)
			)
		)
	)
	(global_label "USB_OTG_ID"
		(shape input)
		(at 222.25 77.47 180)
		(fields_autoplaced yes)
		(effects
			(font
				(size 1.27 1.27)
			)
			(justify right)
		)
		(property "Intersheetrefs" "${INTERSHEET_REFS}"
			(at 208.0767 77.47 0)
			(effects
				(font
					(size 1.27 1.27)
				)
				(justify right)
			)
		)
	)
	(global_label "PCIe_CLK_nREQ"
		(shape input)
		(at 243.84 77.47 0)
		(fields_autoplaced yes)
		(effects
			(font
				(size 1.27 1.27)
			)
			(justify left)
		)
		(property "Intersheetrefs" "${INTERSHEET_REFS}"
			(at 261.4604 77.47 0)
			(effects
				(font
					(size 1.27 1.27)
				)
				(justify left)
			)
		)
	)
	(global_label "HDMI0_HOTPLUG"
		(shape input)
		(at 222.25 143.51 180)
		(fields_autoplaced yes)
		(effects
			(font
				(size 1.27 1.27)
			)
			(justify right)
		)
		(property "Intersheetrefs" "${INTERSHEET_REFS}"
			(at 204.4759 143.4306 0)
			(effects
				(font
					(size 1.27 1.27)
				)
				(justify right)
			)
		)
	)
	(hierarchical_label "DSI1{DSI}"
		(shape bidirectional)
		(at 278.13 189.23 0)
		(effects
			(font
				(size 1.27 1.27)
			)
			(justify left)
		)
	)
	(hierarchical_label "HDMI0{HDMI}"
		(shape bidirectional)
		(at 278.13 158.75 0)
		(effects
			(font
				(size 1.27 1.27)
			)
			(justify left)
		)
	)
	(hierarchical_label "PCIE{PCIe_x4}"
		(shape bidirectional)
		(at 278.13 128.27 0)
		(effects
			(font
				(size 1.27 1.27)
			)
			(justify left)
		)
	)
	(hierarchical_label "CAM0{CSI}"
		(shape bidirectional)
		(at 278.13 105.41 0)
		(effects
			(font
				(size 1.27 1.27)
			)
			(justify left)
		)
	)
	(hierarchical_label "CONN{USB}"
		(shape input)
		(at 179.07 74.93 180)
		(effects
			(font
				(size 1.27 1.27)
			)
			(justify right)
		)
	)
	(hierarchical_label "HDMI0{I^{2}C}"
		(shape bidirectional)
		(at 181.61 196.85 180)
		(effects
			(font
				(size 1.27 1.27)
			)
			(justify right)
		)
	)
	(hierarchical_label "DSI1{DSI}"
		(shape bidirectional)
		(at 181.61 166.37 180)
		(effects
			(font
				(size 1.27 1.27)
			)
			(justify right)
		)
	)
	(hierarchical_label "HDMI0{I^{2}C}"
		(shape bidirectional)
		(at 278.13 196.85 0)
		(effects
			(font
				(size 1.27 1.27)
			)
			(justify left)
		)
	)
	(hierarchical_label "PCIE{PCIe_x4}"
		(shape bidirectional)
		(at 181.61 143.51 180)
		(effects
			(font
				(size 1.27 1.27)
			)
			(justify right)
		)
	)
	(hierarchical_label "CAM1{CSI}"
		(shape bidirectional)
		(at 179.07 90.17 180)
		(effects
			(font
				(size 1.27 1.27)
			)
			(justify right)
		)
	)
	(hierarchical_label "PCIE{PCIe_x4}"
		(shape bidirectional)
		(at 278.13 82.55 0)
		(effects
			(font
				(size 1.27 1.27)
			)
			(justify left)
		)
	)
	(symbol
		(lib_id "antmicropower:GND")
		(at 123.19 160.02 0)
		(unit 1)
		(exclude_from_sim no)
		(in_bom yes)
		(on_board yes)
		(dnp no)
		(fields_autoplaced yes)
		(property "Reference" "#PWR09"
			(at 132.08 162.56 0)
			(effects
				(font
					(size 1.27 1.27)
					(thickness 0.15)
				)
				(justify left bottom)
				(hide yes)
			)
		)
		(property "Value" "GND"
			(at 123.19 165.1 0)
			(effects
				(font
					(size 1.27 1.27)
					(thickness 0.15)
				)
			)
		)
		(property "Footprint" ""
			(at 132.08 167.64 0)
			(effects
				(font
					(size 1.27 1.27)
					(thickness 0.15)
				)
				(justify left bottom)
				(hide yes)
			)
		)
		(property "Datasheet" ""
			(at 132.08 172.72 0)
			(effects
				(font
					(size 1.27 1.27)
					(thickness 0.15)
				)
				(justify left bottom)
				(hide yes)
			)
		)
		(property "Description" ""
			(at 123.19 160.02 0)
			(effects
				(font
					(size 1.27 1.27)
				)
				(hide yes)
			)
		)
		(property "Author" "Antmicro"
			(at 132.08 167.64 0)
			(effects
				(font
					(size 1.27 1.27)
					(thickness 0.15)
				)
				(justify left bottom)
				(hide yes)
			)
		)
		(property "License" "Apache-2.0"
			(at 132.08 170.18 0)
			(effects
				(font
					(size 1.27 1.27)
					(thickness 0.15)
				)
				(justify left bottom)
				(hide yes)
			)
		)
		(pin "1"
		)
		(instances
			(project "polarfire-som"
				(path ""
					(reference "#PWR09")
					(unit 1)
				)
			)
		)
	)
	(symbol
		(lib_id "antmicroResistors0603:R_0R_22.4A_0603")
		(at 110.49 123.19 0)
		(unit 1)
		(exclude_from_sim no)
		(in_bom yes)
		(on_board yes)
		(dnp yes)
		(property "Reference" "R62"
			(at 113.03 118.11 0)
			(effects
				(font
					(size 1.27 1.27)
					(thickness 0.15)
				)
			)
		)
		(property "Value" "R_0R_22.4A_0603"
			(at 113.03 114.3 0)
			(effects
				(font
					(size 1.27 1.27)
					(thickness 0.15)
				)
				(hide yes)
			)
		)
		(property "Footprint" "antmicro-footprints:R_0603_1608Metric"
			(at 125.73 133.35 0)
			(effects
				(font
					(size 1.27 1.27)
					(thickness 0.15)
				)
				(justify left bottom)
				(hide yes)
			)
		)
		(property "Datasheet" "https://fscdn.rohm.com/en/products/databook/datasheet/passive/resistor/chip_resistor/pmr-jpw-e.pdf"
			(at 125.73 135.89 0)
			(effects
				(font
					(size 1.27 1.27)
					(thickness 0.15)
				)
				(justify left bottom)
				(hide yes)
			)
		)
		(property "Description" "SMD Chip Resistor"
			(at 110.49 123.19 0)
			(effects
				(font
					(size 1.27 1.27)
				)
				(hide yes)
			)
		)
		(property "MPN" "PMR03EZPJ000"
			(at 125.73 138.43 0)
			(effects
				(font
					(size 1.27 1.27)
					(thickness 0.15)
				)
				(justify left bottom)
				(hide yes)
			)
		)
		(property "Manufacturer" "ROHM Semiconductor"
			(at 125.73 140.97 0)
			(effects
				(font
					(size 1.27 1.27)
					(thickness 0.15)
				)
				(justify left bottom)
				(hide yes)
			)
		)
		(property "Val" "0R"
			(at 110.49 120.65 0)
			(effects
				(font
					(size 1.27 1.27)
					(thickness 0.15)
				)
			)
		)
		(property "Max. Curr." "22.4A"
			(at 115.57 120.65 0)
			(effects
				(font
					(size 1.27 1.27)
					(thickness 0.15)
				)
			)
		)
		(property "Author" "Antmicro"
			(at 125.73 146.05 0)
			(effects
				(font
					(size 1.27 1.27)
					(thickness 0.15)
				)
				(justify left bottom)
				(hide yes)
			)
		)
		(property "License" "Apache-2.0"
			(at 125.73 148.59 0)
			(effects
				(font
					(size 1.27 1.27)
					(thickness 0.15)
				)
				(justify left bottom)
				(hide yes)
			)
		)
		(property "Tolerance" "template_tolerance"
			(at 130.81 133.35 0)
			(effects
				(font
					(size 1.27 1.27)
				)
				(justify left bottom)
				(hide yes)
			)
		)
		(property "DNP" "DNP"
			(at 113.03 123.19 0)
			(effects
				(font
					(size 1.27 1.27)
				)
				(hide yes)
			)
		)
		(property "Public" ""
			(at 130.81 153.67 0)
			(effects
				(font
					(size 1.27 1.27)
				)
				(justify left bottom)
				(hide yes)
			)
		)
		(pin "1"
		)
		(pin "2"
		)
		(instances
			(project "polarfire-som"
				(path ""
					(reference "R62")
					(unit 1)
				)
			)
		)
	)
	(symbol
		(lib_id "antmicroB2BConnectors:Plug_Hirose_DF40_2x50_DF40C-100DP-0.4V")
		(at 227.33 77.47 0)
		(unit 1)
		(exclude_from_sim no)
		(in_bom yes)
		(on_board yes)
		(dnp no)
		(fields_autoplaced yes)
		(property "Reference" "J4"
			(at 234.315 69.85 0)
			(effects
				(font
					(size 1.27 1.27)
					(thickness 0.15)
				)
			)
		)
		(property "Value" "Plug_Hirose_DF40_2x50_DF40C-100DP-0.4V"
			(at 264.16 82.55 0)
			(effects
				(font
					(size 1.27 1.27)
					(thickness 0.15)
				)
				(justify left bottom)
				(hide yes)
			)
		)
		(property "Footprint" "antmicro-footprints:Conn_Plug_Hirose_DF40_2x50_DF40C-100DP-0.4V"
			(at 264.16 85.09 0)
			(effects
				(font
					(size 1.27 1.27)
					(thickness 0.15)
				)
				(justify left bottom)
				(hide yes)
			)
		)
		(property "Datasheet" "https://www.hirose.com/en/product/document?clcode=CL0684-4032-1-51&productname=DF40C-100DP-0.4V(51)&series=DF40&documenttype=2DDrawing&lang=en&documentid=0001001212"
			(at 264.16 87.63 0)
			(effects
				(font
					(size 1.27 1.27)
					(thickness 0.15)
				)
				(justify left bottom)
				(hide yes)
			)
		)
		(property "Description" "Mezzanine Connector, Header, 0.4 mm, 2 Rows, 100 Contacts, Surface Mount, Phosphor Bronze"
			(at 227.33 77.47 0)
			(effects
				(font
					(size 1.27 1.27)
				)
				(hide yes)
			)
		)
		(property "MPN" "DF40C-100DP-0.4V(51)"
			(at 234.315 72.39 0)
			(effects
				(font
					(size 1.27 1.27)
					(thickness 0.15)
				)
			)
		)
		(property "Manufacturer" "Hirose Electric"
			(at 264.16 90.17 0)
			(effects
				(font
					(size 1.27 1.27)
					(thickness 0.15)
				)
				(justify left bottom)
				(hide yes)
			)
		)
		(property "Pitch" "0.4 mm"
			(at 264.16 92.71 0)
			(effects
				(font
					(size 1.27 1.27)
				)
				(justify left bottom)
				(hide yes)
			)
		)
		(property "Author" "Antmicro"
			(at 264.16 95.25 0)
			(effects
				(font
					(size 1.27 1.27)
					(thickness 0.15)
				)
				(justify left bottom)
				(hide yes)
			)
		)
		(property "License" "Apache-2.0"
			(at 264.16 97.79 0)
			(effects
				(font
					(size 1.27 1.27)
					(thickness 0.15)
				)
				(justify left bottom)
				(hide yes)
			)
		)
		(pin "53"
		)
		(pin "57"
		)
		(pin "89"
		)
		(pin "25"
		)
		(pin "67"
		)
		(pin "27"
		)
		(pin "56"
		)
		(pin "79"
		)
		(pin "29"
		)
		(pin "43"
		)
		(pin "93"
		)
		(pin "10"
		)
		(pin "20"
		)
		(pin "19"
		)
		(pin "41"
		)
		(pin "11"
		)
		(pin "100"
		)
		(pin "13"
		)
		(pin "18"
		)
		(pin "40"
		)
		(pin "12"
		)
		(pin "1"
		)
		(pin "22"
		)
		(pin "17"
		)
		(pin "80"
		)
		(pin "64"
		)
		(pin "26"
		)
		(pin "6"
		)
		(pin "87"
		)
		(pin "3"
		)
		(pin "52"
		)
		(pin "35"
		)
		(pin "55"
		)
		(pin "94"
		)
		(pin "76"
		)
		(pin "5"
		)
		(pin "73"
		)
		(pin "71"
		)
		(pin "47"
		)
		(pin "88"
		)
		(pin "95"
		)
		(pin "14"
		)
		(pin "MP"
		)
		(pin "99"
		)
		(pin "85"
		)
		(pin "84"
		)
		(pin "86"
		)
		(pin "24"
		)
		(pin "59"
		)
		(pin "90"
		)
		(pin "77"
		)
		(pin "78"
		)
		(pin "69"
		)
		(pin "65"
		)
		(pin "68"
		)
		(pin "74"
		)
		(pin "60"
		)
		(pin "72"
		)
		(pin "98"
		)
		(pin "66"
		)
		(pin "45"
		)
		(pin "58"
		)
		(pin "50"
		)
		(pin "61"
		)
		(pin "62"
		)
		(pin "44"
		)
		(pin "82"
		)
		(pin "2"
		)
		(pin "96"
		)
		(pin "42"
		)
		(pin "81"
		)
		(pin "63"
		)
		(pin "97"
		)
		(pin "15"
		)
		(pin "16"
		)
		(pin "21"
		)
		(pin "36"
		)
		(pin "38"
		)
		(pin "75"
		)
		(pin "70"
		)
		(pin "8"
		)
		(pin "9"
		)
		(pin "92"
		)
		(pin "32"
		)
		(pin "31"
		)
		(pin "39"
		)
		(pin "33"
		)
		(pin "51"
		)
		(pin "4"
		)
		(pin "54"
		)
		(pin "34"
		)
		(pin "37"
		)
		(pin "28"
		)
		(pin "30"
		)
		(pin "91"
		)
		(pin "23"
		)
		(pin "48"
		)
		(pin "83"
		)
		(pin "7"
		)
		(pin "49"
		)
		(pin "46"
		)
		(instances
			(project "polarfire-som"
				(path ""
					(reference "J4")
					(unit 1)
				)
			)
		)
	)
	(symbol
		(lib_id "antmicropower:PWR_FLAG")
		(at 130.81 133.35 0)
		(unit 1)
		(exclude_from_sim no)
		(in_bom yes)
		(on_board yes)
		(dnp no)
		(property "Reference" "#FLG03"
			(at 130.81 131.445 0)
			(effects
				(font
					(size 1.27 1.27)
				)
				(hide yes)
			)
		)
		(property "Value" "PWR_FLAG"
			(at 130.81 125.73 90)
			(effects
				(font
					(size 1.27 1.27)
				)
			)
		)
		(property "Footprint" ""
			(at 130.81 133.35 0)
			(effects
				(font
					(size 1.27 1.27)
				)
				(hide yes)
			)
		)
		(property "Datasheet" ""
			(at 130.81 133.35 0)
			(effects
				(font
					(size 1.27 1.27)
				)
				(hide yes)
			)
		)
		(property "Description" ""
			(at 130.81 133.35 0)
			(effects
				(font
					(size 1.27 1.27)
				)
				(hide yes)
			)
		)
		(pin "1"
		)
		(instances
			(project "polarfire-som"
				(path ""
					(reference "#FLG03")
					(unit 1)
				)
			)
		)
	)
	(symbol
		(lib_id "antmicropower:+5V")
		(at 96.52 134.62 90)
		(unit 1)
		(exclude_from_sim no)
		(in_bom yes)
		(on_board yes)
		(dnp no)
		(property "Reference" "#PWR02"
			(at 99.06 119.38 0)
			(effects
				(font
					(size 1.27 1.27)
					(thickness 0.15)
				)
				(justify left bottom)
				(hide yes)
			)
		)
		(property "Value" "+5V"
			(at 91.44 134.62 90)
			(effects
				(font
					(size 1.27 1.27)
					(thickness 0.15)
				)
			)
		)
		(property "Footprint" ""
			(at 104.14 119.38 0)
			(effects
				(font
					(size 1.27 1.27)
					(thickness 0.15)
				)
				(justify left bottom)
				(hide yes)
			)
		)
		(property "Datasheet" ""
			(at 106.68 119.38 0)
			(effects
				(font
					(size 1.27 1.27)
					(thickness 0.15)
				)
				(justify left bottom)
				(hide yes)
			)
		)
		(property "Description" ""
			(at 96.52 134.62 0)
			(effects
				(font
					(size 1.27 1.27)
				)
				(hide yes)
			)
		)
		(property "Author" "Antmicro"
			(at 104.14 119.38 0)
			(effects
				(font
					(size 1.27 1.27)
					(thickness 0.15)
				)
				(justify left bottom)
				(hide yes)
			)
		)
		(property "License" "Apache-2.0"
			(at 106.68 119.38 0)
			(effects
				(font
					(size 1.27 1.27)
					(thickness 0.15)
				)
				(justify left bottom)
				(hide yes)
			)
		)
		(pin "1"
		)
		(instances
			(project "polarfire-som"
				(path ""
					(reference "#PWR02")
					(unit 1)
				)
			)
		)
	)
	(symbol
		(lib_id "antmicropower:GND")
		(at 224.79 208.28 0)
		(unit 1)
		(exclude_from_sim no)
		(in_bom yes)
		(on_board yes)
		(dnp no)
		(fields_autoplaced yes)
		(property "Reference" "#PWR0214"
			(at 233.68 210.82 0)
			(effects
				(font
					(size 1.27 1.27)
					(thickness 0.15)
				)
				(justify left bottom)
				(hide yes)
			)
		)
		(property "Value" "GND"
			(at 224.79 213.36 0)
			(effects
				(font
					(size 1.27 1.27)
					(thickness 0.15)
				)
			)
		)
		(property "Footprint" ""
			(at 233.68 215.9 0)
			(effects
				(font
					(size 1.27 1.27)
					(thickness 0.15)
				)
				(justify left bottom)
				(hide yes)
			)
		)
		(property "Datasheet" ""
			(at 233.68 220.98 0)
			(effects
				(font
					(size 1.27 1.27)
					(thickness 0.15)
				)
				(justify left bottom)
				(hide yes)
			)
		)
		(property "Description" ""
			(at 224.79 208.28 0)
			(effects
				(font
					(size 1.27 1.27)
				)
				(hide yes)
			)
		)
		(property "Author" "Antmicro"
			(at 233.68 215.9 0)
			(effects
				(font
					(size 1.27 1.27)
					(thickness 0.15)
				)
				(justify left bottom)
				(hide yes)
			)
		)
		(property "License" "Apache-2.0"
			(at 233.68 218.44 0)
			(effects
				(font
					(size 1.27 1.27)
					(thickness 0.15)
				)
				(justify left bottom)
				(hide yes)
			)
		)
		(pin "1"
		)
		(instances
			(project "polarfire-som"
				(path ""
					(reference "#PWR0214")
					(unit 1)
				)
			)
		)
	)
	(symbol
		(lib_id "antmicroPMICORControllersIdealDiodes:DZDH0401DW")
		(at 121.92 148.59 0)
		(mirror y)
		(unit 1)
		(exclude_from_sim no)
		(in_bom yes)
		(on_board yes)
		(dnp no)
		(property "Reference" "Q3"
			(at 113.665 142.24 0)
			(effects
				(font
					(size 1.27 1.27)
					(thickness 0.15)
				)
			)
		)
		(property "Value" "DZDH0401DW"
			(at 113.665 144.78 0)
			(effects
				(font
					(size 1.27 1.27)
					(thickness 0.15)
				)
			)
		)
		(property "Footprint" "antmicro-footprints:SOT-363"
			(at 91.44 158.75 0)
			(effects
				(font
					(size 1.27 1.27)
					(thickness 0.15)
				)
				(justify left bottom)
				(hide yes)
			)
		)
		(property "Datasheet" "https://www.mouser.com/datasheet/2/115/DIOD_S_A0011803041_1-2543705.pdf"
			(at 91.44 161.29 0)
			(effects
				(font
					(size 1.27 1.27)
					(thickness 0.15)
				)
				(justify left bottom)
				(hide yes)
			)
		)
		(property "Description" "OR Controller N+1 ORing Controller P-Channel 1:1 SOT-363"
			(at 121.92 148.59 0)
			(effects
				(font
					(size 1.27 1.27)
				)
				(hide yes)
			)
		)
		(property "MPN" "DZDH0401DW"
			(at 91.44 163.83 0)
			(effects
				(font
					(size 1.27 1.27)
					(thickness 0.15)
				)
				(justify left bottom)
				(hide yes)
			)
		)
		(property "Manufacturer" "Diodes Incorporated"
			(at 91.44 166.37 0)
			(effects
				(font
					(size 1.27 1.27)
					(thickness 0.15)
				)
				(justify left bottom)
				(hide yes)
			)
		)
		(property "Author" "Antmicro"
			(at 91.44 168.91 0)
			(effects
				(font
					(size 1.27 1.27)
					(thickness 0.15)
				)
				(justify left bottom)
				(hide yes)
			)
		)
		(property "License" "Apache-2.0"
			(at 91.44 171.45 0)
			(effects
				(font
					(size 1.27 1.27)
					(thickness 0.15)
				)
				(justify left bottom)
				(hide yes)
			)
		)
		(pin "6"
		)
		(pin "4"
		)
		(pin "3"
		)
		(pin "2"
		)
		(pin "1"
		)
		(pin "5"
		)
		(instances
			(project "polarfire-som"
				(path ""
					(reference "Q3")
					(unit 1)
				)
			)
		)
	)
	(symbol
		(lib_id "antmicropower:GND")
		(at 100.33 160.02 0)
		(unit 1)
		(exclude_from_sim no)
		(in_bom yes)
		(on_board yes)
		(dnp no)
		(property "Reference" "#PWR08"
			(at 109.22 162.56 0)
			(effects
				(font
					(size 1.27 1.27)
					(thickness 0.15)
				)
				(justify left bottom)
				(hide yes)
			)
		)
		(property "Value" "GND"
			(at 100.33 165.1 0)
			(effects
				(font
					(size 1.27 1.27)
					(thickness 0.15)
				)
			)
		)
		(property "Footprint" ""
			(at 109.22 167.64 0)
			(effects
				(font
					(size 1.27 1.27)
					(thickness 0.15)
				)
				(justify left bottom)
				(hide yes)
			)
		)
		(property "Datasheet" ""
			(at 109.22 172.72 0)
			(effects
				(font
					(size 1.27 1.27)
					(thickness 0.15)
				)
				(justify left bottom)
				(hide yes)
			)
		)
		(property "Description" ""
			(at 100.33 160.02 0)
			(effects
				(font
					(size 1.27 1.27)
				)
				(hide yes)
			)
		)
		(property "Author" "Antmicro"
			(at 109.22 167.64 0)
			(effects
				(font
					(size 1.27 1.27)
					(thickness 0.15)
				)
				(justify left bottom)
				(hide yes)
			)
		)
		(property "License" "Apache-2.0"
			(at 109.22 170.18 0)
			(effects
				(font
					(size 1.27 1.27)
					(thickness 0.15)
				)
				(justify left bottom)
				(hide yes)
			)
		)
		(pin "1"
		)
		(instances
			(project "polarfire-som"
				(path ""
					(reference "#PWR08")
					(unit 1)
				)
			)
		)
	)
	(symbol
		(lib_id "antmicroResistors0402:R_100k_0402")
		(at 123.19 158.75 90)
		(unit 1)
		(exclude_from_sim no)
		(in_bom yes)
		(on_board yes)
		(dnp no)
		(fields_autoplaced yes)
		(property "Reference" "R63"
			(at 125.73 154.94 90)
			(effects
				(font
					(size 1.27 1.27)
					(thickness 0.15)
				)
				(justify right)
			)
		)
		(property "Value" "R_100k_0402"
			(at 135.89 138.43 0)
			(effects
				(font
					(size 1.27 1.27)
					(thickness 0.15)
				)
				(justify left bottom)
				(hide yes)
			)
		)
		(property "Footprint" "antmicro-footprints:R_0402_1005Metric"
			(at 138.43 138.43 0)
			(effects
				(font
					(size 1.27 1.27)
					(thickness 0.15)
				)
				(justify left bottom)
				(hide yes)
			)
		)
		(property "Datasheet" "https://www.bourns.com/docs/product-datasheets/cr.pdf"
			(at 140.97 138.43 0)
			(effects
				(font
					(size 1.27 1.27)
					(thickness 0.15)
				)
				(justify left bottom)
				(hide yes)
			)
		)
		(property "Description" "SMD Chip Resistor, 100 kohm, ± 1%, 62.5 mW, 0402 [1005 Metric], Thick Film, General Purpose"
			(at 123.19 158.75 0)
			(effects
				(font
					(size 1.27 1.27)
				)
				(hide yes)
			)
		)
		(property "MPN" "CR0402-FX-1003GLF"
			(at 143.51 138.43 0)
			(effects
				(font
					(size 1.27 1.27)
					(thickness 0.15)
				)
				(justify left bottom)
				(hide yes)
			)
		)
		(property "Manufacturer" "Bourns"
			(at 146.05 138.43 0)
			(effects
				(font
					(size 1.27 1.27)
					(thickness 0.15)
				)
				(justify left bottom)
				(hide yes)
			)
		)
		(property "License" "Apache-2.0"
			(at 148.59 138.43 0)
			(effects
				(font
					(size 1.27 1.27)
					(thickness 0.15)
				)
				(justify left bottom)
				(hide yes)
			)
		)
		(property "Author" "Antmicro"
			(at 151.13 138.43 0)
			(effects
				(font
					(size 1.27 1.27)
					(thickness 0.15)
				)
				(justify left bottom)
				(hide yes)
			)
		)
		(property "Val" "100k"
			(at 125.73 157.48 90)
			(effects
				(font
					(size 1.27 1.27)
					(thickness 0.15)
				)
				(justify right)
			)
		)
		(property "Tolerance" "1%"
			(at 133.35 138.43 0)
			(effects
				(font
					(size 1.27 1.27)
				)
				(justify left bottom)
				(hide yes)
			)
		)
		(property "Public" ""
			(at 153.67 138.43 0)
			(effects
				(font
					(size 1.27 1.27)
				)
				(justify left bottom)
				(hide yes)
			)
		)
		(pin "1"
		)
		(pin "2"
		)
		(instances
			(project "polarfire-som"
				(path ""
					(reference "R63")
					(unit 1)
				)
			)
		)
	)
	(symbol
		(lib_id "antmicropower:GND")
		(at 243.84 208.28 0)
		(unit 1)
		(exclude_from_sim no)
		(in_bom yes)
		(on_board yes)
		(dnp no)
		(fields_autoplaced yes)
		(property "Reference" "#PWR0218"
			(at 252.73 210.82 0)
			(effects
				(font
					(size 1.27 1.27)
					(thickness 0.15)
				)
				(justify left bottom)
				(hide yes)
			)
		)
		(property "Value" "GND"
			(at 243.84 213.36 0)
			(effects
				(font
					(size 1.27 1.27)
					(thickness 0.15)
				)
			)
		)
		(property "Footprint" ""
			(at 252.73 215.9 0)
			(effects
				(font
					(size 1.27 1.27)
					(thickness 0.15)
				)
				(justify left bottom)
				(hide yes)
			)
		)
		(property "Datasheet" ""
			(at 252.73 220.98 0)
			(effects
				(font
					(size 1.27 1.27)
					(thickness 0.15)
				)
				(justify left bottom)
				(hide yes)
			)
		)
		(property "Description" ""
			(at 243.84 208.28 0)
			(effects
				(font
					(size 1.27 1.27)
				)
				(hide yes)
			)
		)
		(property "Author" "Antmicro"
			(at 252.73 215.9 0)
			(effects
				(font
					(size 1.27 1.27)
					(thickness 0.15)
				)
				(justify left bottom)
				(hide yes)
			)
		)
		(property "License" "Apache-2.0"
			(at 252.73 218.44 0)
			(effects
				(font
					(size 1.27 1.27)
					(thickness 0.15)
				)
				(justify left bottom)
				(hide yes)
			)
		)
		(pin "1"
		)
		(instances
			(project "polarfire-som"
				(path ""
					(reference "#PWR0218")
					(unit 1)
				)
			)
		)
	)
	(symbol
		(lib_id "antmicroResistors0402:R_1M_0402")
		(at 100.33 158.75 90)
		(unit 1)
		(exclude_from_sim no)
		(in_bom yes)
		(on_board yes)
		(dnp no)
		(fields_autoplaced yes)
		(property "Reference" "R61"
			(at 102.87 154.94 90)
			(effects
				(font
					(size 1.27 1.27)
					(thickness 0.15)
				)
				(justify right)
			)
		)
		(property "Value" "R_1M_0402"
			(at 113.03 138.43 0)
			(effects
				(font
					(size 1.27 1.27)
					(thickness 0.15)
				)
				(justify left bottom)
				(hide yes)
			)
		)
		(property "Footprint" "antmicro-footprints:R_0402_1005Metric"
			(at 115.57 138.43 0)
			(effects
				(font
					(size 1.27 1.27)
					(thickness 0.15)
				)
				(justify left bottom)
				(hide yes)
			)
		)
		(property "Datasheet" "https://www.bourns.com/docs/product-datasheets/cr.pdf"
			(at 118.11 138.43 0)
			(effects
				(font
					(size 1.27 1.27)
					(thickness 0.15)
				)
				(justify left bottom)
				(hide yes)
			)
		)
		(property "Description" "SMD Chip Resistor, 1 Mohm, ± 1%, 62.5 mW, 0402 [1005 Metric], Thick Film, General Purpose"
			(at 100.33 158.75 0)
			(effects
				(font
					(size 1.27 1.27)
				)
				(hide yes)
			)
		)
		(property "MPN" "CR0402-FX-1004GLF"
			(at 120.65 138.43 0)
			(effects
				(font
					(size 1.27 1.27)
					(thickness 0.15)
				)
				(justify left bottom)
				(hide yes)
			)
		)
		(property "Manufacturer" "Bourns"
			(at 123.19 138.43 0)
			(effects
				(font
					(size 1.27 1.27)
					(thickness 0.15)
				)
				(justify left bottom)
				(hide yes)
			)
		)
		(property "License" "Apache-2.0"
			(at 125.73 138.43 0)
			(effects
				(font
					(size 1.27 1.27)
					(thickness 0.15)
				)
				(justify left bottom)
				(hide yes)
			)
		)
		(property "Author" "Antmicro"
			(at 128.27 138.43 0)
			(effects
				(font
					(size 1.27 1.27)
					(thickness 0.15)
				)
				(justify left bottom)
				(hide yes)
			)
		)
		(property "Val" "1M"
			(at 102.87 157.48 90)
			(effects
				(font
					(size 1.27 1.27)
					(thickness 0.15)
				)
				(justify right)
			)
		)
		(property "Tolerance" "1%"
			(at 110.49 138.43 0)
			(effects
				(font
					(size 1.27 1.27)
				)
				(justify left bottom)
				(hide yes)
			)
		)
		(property "Public" ""
			(at 130.81 138.43 0)
			(effects
				(font
					(size 1.27 1.27)
				)
				(justify left bottom)
				(hide yes)
			)
		)
		(pin "2"
		)
		(pin "1"
		)
		(instances
			(project "polarfire-som"
				(path ""
					(reference "R61")
					(unit 1)
				)
			)
		)
	)
	(symbol
		(lib_id "antmicroTransistorsFETsMOSFETsSingle:AO3401A")
		(at 110.49 142.24 270)
		(mirror x)
		(unit 1)
		(exclude_from_sim no)
		(in_bom yes)
		(on_board yes)
		(dnp no)
		(property "Reference" "Q9"
			(at 113.03 128.27 90)
			(effects
				(font
					(size 1.27 1.27)
					(thickness 0.15)
				)
			)
		)
		(property "Value" "AO3401A"
			(at 113.03 130.81 90)
			(effects
				(font
					(size 1.27 1.27)
					(thickness 0.15)
				)
			)
		)
		(property "Footprint" "antmicro-footprints:SOT-23-3"
			(at 99.06 119.38 0)
			(effects
				(font
					(size 1.27 1.27)
					(thickness 0.15)
				)
				(justify left bottom)
				(hide yes)
			)
		)
		(property "Datasheet" "http://aosmd.com/res/data_sheets/AO3401A.pdf"
			(at 96.52 119.38 0)
			(effects
				(font
					(size 1.27 1.27)
					(thickness 0.15)
				)
				(justify left bottom)
				(hide yes)
			)
		)
		(property "Description" "Power MOSFET, P Channel, 30 V, 4 A, 0.07 ohm, SOT-23, Surface Mount"
			(at 110.49 142.24 0)
			(effects
				(font
					(size 1.27 1.27)
				)
				(hide yes)
			)
		)
		(property "MPN" "AO3401A"
			(at 93.98 119.38 0)
			(effects
				(font
					(size 1.27 1.27)
					(thickness 0.15)
				)
				(justify left bottom)
				(hide yes)
			)
		)
		(property "Manufacturer" "AOSMD"
			(at 91.44 119.38 0)
			(effects
				(font
					(size 1.27 1.27)
					(thickness 0.15)
				)
				(justify left bottom)
				(hide yes)
			)
		)
		(property "Author" "Antmicro"
			(at 88.9 119.38 0)
			(effects
				(font
					(size 1.27 1.27)
					(thickness 0.15)
				)
				(justify left bottom)
				(hide yes)
			)
		)
		(property "License" "Apache-2.0"
			(at 86.36 119.38 0)
			(effects
				(font
					(size 1.27 1.27)
					(thickness 0.15)
				)
				(justify left bottom)
				(hide yes)
			)
		)
		(pin "2"
		)
		(pin "1"
		)
		(pin "3"
		)
		(instances
			(project "polarfire-som"
				(path ""
					(reference "Q9")
					(unit 1)
				)
			)
		)
	)
)
